G04 ================== begin FILE IDENTIFICATION RECORD ==================*
G04 Layout Name:  15968-1a.brd*
G04 Film Name:    DP_REF_L6*
G04 File Format:  Gerber RS274X*
G04 File Origin:  Cadence Allegro 16.5-S058*
G04 Origin Date:  Fri Oct 14 10:23:55 2016*
G04 *
G04 Layer:  BOARD GEOMETRY/DP_REF_L6_TBL*
G04 Layer:  BOARD GEOMETRY/DP_REF_L6_BOTTOM*
G04 Layer:  BOARD GEOMETRY/PANEL_OUTLINE*
G04 *
G04 Offset:    (0.00 0.00)*
G04 Mirror:    No*
G04 Mode:      Positive*
G04 Rotation:  0*
G04 FullContactRelief:  No*
G04 UndefLineWidth:     6.00*
G04 ================== end FILE IDENTIFICATION RECORD ====================*
%FSLAX35Y35*MOIN*%
%IR0*IPPOS*OFA0.00000B0.00000*MIA0B0*SFA1.00000B1.00000*%
%ADD10C,.02*%
%ADD11C,.005*%
%ADD12C,.006*%
G75*
%LPD*%
G75*
G54D10*
G01X687653Y496146D02*
X1212653D01*
G01X687653Y461496D02*
X1212653D01*
G01X687653Y426846D02*
X1212653D01*
G01X687653Y530796D02*
Y426846D01*
G01Y530796D02*
X1212653D01*
G01X862653D02*
Y426846D01*
G01X1107653Y530796D02*
Y426846D01*
G01X1212653Y530796D02*
Y426846D01*
G54D11*
G01X-21653Y-58346D02*
G03X-6653Y-73346I15000J0D01*
G01X65080D02*
X-6653D01*
G01X9506Y0D02*
X69017D01*
G01X6722Y1153D02*
G03X9506Y0I2784J2784D01*
G01X1154Y6721D02*
X6722Y1153D01*
G01X1Y9505D02*
G03X1154Y6721I3937J0D01*
G01X1Y238051D02*
Y9505D01*
G01Y238051D02*
Y9505D01*
G01X-21653Y238051D02*
Y9505D01*
G01X1D02*
G03X1154Y6721I3937J0D01*
G01X-7873Y9505D02*
G03X-4414Y1153I11811J-1D01*
G01X1154Y6721D02*
X6722Y1153D01*
G01X-4414D02*
X1154Y-4415D01*
G01X6722Y1153D02*
G03X9506Y0I2784J2784D01*
G01X1154Y-4415D02*
G03X9506Y-7874I8351J8352D01*
G01Y0D02*
X69017D01*
G01X9506Y-7874D02*
X14917D01*
G01X-21653Y9505D02*
Y-58346D01*
G01X14917Y-7874D02*
G03Y0I0J3937D01*
G01X-7873Y50852D02*
Y9505D01*
G01Y81561D02*
G03X1I3937J-1D01*
G01Y50852D02*
G03X-7873I-3937J0D01*
G01Y186482D02*
Y81561D01*
G01X13443Y249862D02*
X611812D01*
G01X10659Y251015D02*
G03X13443Y249862I2784J2784D01*
G01X1154Y260520D02*
X10659Y251015D01*
G01X3938Y241988D02*
G03X1Y238051I0J-3937D01*
G01X602307Y241988D02*
X3938D01*
G01X602307D02*
X3938D01*
G01D02*
G03X1Y238051I0J-3937D01*
G01X-7873D02*
Y217191D01*
G01X1154Y260520D02*
X10659Y251015D01*
G01D02*
G03X13443Y249862I2784J2784D01*
G01D02*
X611812D01*
G01X-21653Y238051D02*
Y534327D01*
G01X-7873Y238051D02*
Y263304D01*
G01Y217191D02*
G03X1I3937J-1D01*
G01Y186482D02*
G03X-7873I-3937J0D01*
G01X1Y263304D02*
G03X1154Y260520I3937J0D01*
G01X1Y328602D02*
Y263304D01*
G01X3938Y332539D02*
G03X1Y328602I0J-3937D01*
G01X53151Y332539D02*
X3938D01*
G01X53151D02*
X3938D01*
G01D02*
G03X1Y328602I0J-3937D01*
G01X3938Y340413D02*
G03X-7873Y328602I0J-11811D01*
G01X1D02*
Y263304D01*
G01X-7873Y328602D02*
Y263304D01*
G01X1D02*
G03X1154Y260520I3937J0D01*
G01X10965Y332539D02*
G03Y340413I0J3937D01*
G01D02*
X3938D01*
G01X-6653Y565196D02*
G03X-21653Y550196I0J-15000D01*
G01X67796Y565196D02*
X-6653D01*
G01X-21653Y542201D02*
Y550196D01*
G01Y534327D02*
G03Y542201I0J3937D01*
G01X74922Y-73346D02*
X175828D01*
G01X72954Y-71378D02*
X74922Y-73346D01*
G01X72954Y-3937D02*
Y-71378D01*
G01X65080Y-7874D02*
Y-71772D01*
G01D02*
Y-73346D01*
G01X72954Y-3937D02*
G03X69017Y0I-3937J0D01*
G01X72954Y-3937D02*
G03X69017Y0I-3937J0D01*
G01X45626D02*
G03Y-7874I0J-3937D01*
G01D02*
X65080D01*
G01X51397Y241988D02*
G03Y249862I0J3937D01*
G01X93906D02*
G03Y241988I0J-3937D01*
G01X53151Y332539D02*
G03X57088Y336476I0J3937D01*
G01Y482345D02*
Y336476D01*
G01Y482345D02*
Y336476D01*
G01X53151Y332539D02*
G03X57088Y336476I0J3937D01*
G01X41674Y340413D02*
G03Y332539I0J-3937D01*
G01X49214Y340413D02*
X41674D01*
G01X49214Y442487D02*
Y340413D01*
G01X67796Y565196D02*
Y499724D01*
G01X75670Y563228D02*
Y495787D01*
G01X58241Y485129D02*
G03X57088Y482345I2784J-2784D01*
G01X63808Y490697D02*
X58241Y485129D01*
G01X66592Y491850D02*
G03X63808Y490697I0J-3937D01*
G01X71733Y491850D02*
X66592D01*
G01X71733D02*
G03X75670Y495787I0J3937D01*
G01X67796Y499724D02*
X66592D01*
G01Y491850D02*
G03X63808Y490697I0J-3937D01*
G01X66592Y499724D02*
G03X58240Y496265I-1J-11811D01*
G01X63808Y490697D02*
X58241Y485129D01*
G01X58240Y496264D02*
X52673Y490696D01*
G01X58241Y485129D02*
G03X57088Y482345I2784J-2784D01*
G01X52673Y490697D02*
G03X49214Y482343I8352J-8351D01*
G01Y482345D02*
Y473195D01*
G01X57088Y442487D02*
G03X49214I-3937J-1D01*
G01Y473195D02*
G03X57088I3937J0D01*
G01X77639Y565196D02*
X75670Y563228D01*
G01X173111Y565196D02*
X77639D01*
G01X177796Y-71378D02*
Y-52874D01*
G01X175828Y-73346D02*
X177796Y-71378D01*
G01X180641Y1939D02*
X194380Y78798D01*
G01X195600Y78800D02*
X181800Y1600D01*
G01X164884Y-39492D02*
X180641Y1939D01*
G01X181800Y1600D02*
X164581Y-43669D01*
G01X159914Y-52561D02*
X162304Y-46278D01*
G01X162000Y-50454D02*
X161073Y-52890D01*
G01X163557Y-46360D02*
X163023Y-47762D01*
G01X159873Y-56928D02*
Y-52669D01*
G01X161073Y-52890D02*
Y-57284D01*
G01X169322Y-55830D02*
Y-56806D01*
G01X170522Y-56804D02*
Y-55604D01*
G01X168483Y-53685D02*
X169321Y-55830D01*
G01X170522Y-55604D02*
X169700Y-53500D01*
G01X168715Y-50439D02*
X168483Y-53685D01*
G01X169700Y-53500D02*
X169900Y-50700D01*
G01X169804Y-47559D02*
X168715Y-50439D01*
G01X169900Y-50700D02*
X188800Y-700D01*
G01X171352Y-43462D02*
X170822Y-44865D01*
G01X169900Y-50700D02*
X188800Y-700D01*
G01X187641Y-370D02*
X172371Y-40768D01*
G01X169900Y-50700D02*
X188800Y-700D01*
G01X161073Y-52890D02*
Y-57284D01*
G01X159873Y-56928D02*
Y-52669D01*
G01X162000Y-50454D02*
X161073Y-52890D01*
G01X159914Y-52561D02*
X162304Y-46278D01*
G01X163557Y-46360D02*
X163023Y-47762D01*
G01X159914Y-52561D02*
X162304Y-46278D01*
G01X181800Y1600D02*
X164581Y-43669D01*
G01X164884Y-39492D02*
X180641Y1939D01*
G01X195600Y78800D02*
X181800Y1600D01*
G01X180641Y1939D02*
X194380Y78798D01*
G01X169900Y-50700D02*
X188800Y-700D01*
G01X169804Y-47559D02*
X168715Y-50439D01*
G01X171352Y-43462D02*
X170822Y-44865D01*
G01X187641Y-370D02*
X172371Y-40768D01*
G01X169700Y-53500D02*
X169900Y-50700D01*
G01X168715Y-50439D02*
X168483Y-53685D01*
G01X170522Y-55604D02*
X169700Y-53500D01*
G01X168483Y-53685D02*
X169321Y-55830D01*
G01X170522Y-56804D02*
Y-55604D01*
G01X169322Y-55830D02*
Y-56806D01*
G01X177258Y14359D02*
X187573Y78734D01*
G01X188800Y78800D02*
X178400Y13900D01*
G01X139406Y-40371D02*
X177258Y14359D01*
G01X178400Y13900D02*
X133100Y-51600D01*
G01X137768Y-42740D02*
X139406Y-40371D01*
G01X178400Y13900D02*
X133100Y-51600D01*
G01X136915Y-43973D02*
X137768Y-42740D01*
G01X178400Y13900D02*
X133100Y-51600D01*
G01X134423Y-47576D02*
X135277Y-46342D01*
G01X178400Y13900D02*
X133100Y-51600D01*
G01X131932Y-51178D02*
X132785Y-49944D01*
G01X178400Y13900D02*
X133100Y-51600D01*
G01X131904Y-51495D02*
X131932Y-51178D01*
G01X133100Y-51600D02*
X132726Y-55822D01*
G01X131526Y-55768D02*
X131904Y-51495D01*
G01X133100Y-51600D02*
X132726Y-55822D01*
G01X131526Y-57491D02*
Y-55768D01*
G01X132726Y-55822D02*
Y-57237D01*
G01Y-55822D02*
Y-57237D01*
G01X131526Y-57491D02*
Y-55768D01*
G01X133100Y-51600D02*
X132726Y-55822D01*
G01X131904Y-51495D02*
X131932Y-51178D01*
G01X131526Y-55768D02*
X131904Y-51495D01*
G01X178400Y13900D02*
X133100Y-51600D01*
G01X139406Y-40371D02*
X177258Y14359D01*
G01X137768Y-42740D02*
X139406Y-40371D01*
G01X136915Y-43973D02*
X137768Y-42740D01*
G01X134423Y-47576D02*
X135277Y-46342D01*
G01X131932Y-51178D02*
X132785Y-49944D01*
G01X188800Y78800D02*
X178400Y13900D01*
G01X177258Y14359D02*
X187573Y78734D01*
G01X187245Y-52874D02*
G03X177796I-4725J0D01*
G01X187573Y78734D02*
X176942Y117584D01*
G01X178100Y117900D02*
X188800Y78800D01*
G01X178100Y117900D02*
X188800Y78800D01*
G01X187573Y78734D02*
X176942Y117584D01*
G01X176085Y175404D02*
X175224Y182728D01*
G01X176416Y182868D02*
X177263Y175666D01*
G01X184404Y158608D02*
X176134Y175240D01*
G01X177263Y175666D02*
X185627Y158846D01*
G01X184435Y158566D02*
X184430Y158589D01*
G01X185613Y158795D02*
X185661Y158551D01*
G01X184531Y158075D02*
X184435Y158566D01*
G01X185709Y158305D02*
X186033Y156643D01*
G01X185661Y158551D02*
X185709Y158305D01*
G01X185613Y158795D02*
X185661Y158551D01*
G01X184823Y156575D02*
X184531Y158075D01*
G01X185709Y158305D02*
X186033Y156643D01*
G01X185661Y158551D02*
X185709Y158305D01*
G01X184736Y155492D02*
X184823Y156575D01*
G01X186033Y156643D02*
X185925Y155297D01*
G01X184401Y154154D02*
X184736Y155492D01*
G01X185900Y155200D02*
X185500Y153600D01*
G01X181617Y150774D02*
X184401Y154154D01*
G01X185500Y153600D02*
X182700Y150200D01*
G01X181002Y148682D02*
X181617Y150774D01*
G01X182700Y150200D02*
X182200Y148500D01*
G01X180855Y138997D02*
X181002Y148682D01*
G01X182200Y148500D02*
X182054Y138909D01*
G01X180642Y137377D02*
X180855Y138997D01*
G01X182054Y138909D02*
X181791Y136908D01*
G01X178681Y134773D02*
X180642Y137377D01*
G01X179641Y134052D02*
X179344Y133656D01*
G01X181791Y136908D02*
X179641Y134052D01*
G01X178530Y134572D02*
X178681Y134773D01*
G01X179641Y134052D02*
X179344Y133656D01*
G01X181791Y136908D02*
X179641Y134052D01*
G01X178383Y134375D02*
X178530Y134572D01*
G01X179641Y134052D02*
X179344Y133656D01*
G01X177223Y132359D02*
X178371Y134370D01*
G01X179338Y133642D02*
X178384Y131972D01*
G01X176872Y129552D02*
X177223Y132359D01*
G01X178384Y131972D02*
X178063Y129405D01*
G01X176863Y129480D02*
X176872Y129552D01*
G01X178384Y131972D02*
X178063Y129405D01*
G01X176863Y117870D02*
Y129480D01*
G01X178063Y129405D02*
Y118034D01*
G01Y129405D02*
Y118034D01*
G01X176863Y117870D02*
Y129480D01*
G01X178384Y131972D02*
X178063Y129405D01*
G01X176872Y129552D02*
X177223Y132359D01*
G01X176863Y129480D02*
X176872Y129552D01*
G01X179338Y133642D02*
X178384Y131972D01*
G01X177223Y132359D02*
X178371Y134370D01*
G01X179641Y134052D02*
X179344Y133656D01*
G01X178681Y134773D02*
X180642Y137377D01*
G01X178530Y134572D02*
X178681Y134773D01*
G01X178383Y134375D02*
X178530Y134572D01*
G01X181791Y136908D02*
X179641Y134052D01*
G01X178681Y134773D02*
X180642Y137377D01*
G01X178530Y134572D02*
X178681Y134773D01*
G01X182054Y138909D02*
X181791Y136908D01*
G01X180642Y137377D02*
X180855Y138997D01*
G01X182200Y148500D02*
X182054Y138909D01*
G01X180855Y138997D02*
X181002Y148682D01*
G01X182700Y150200D02*
X182200Y148500D01*
G01X181002Y148682D02*
X181617Y150774D01*
G01X185500Y153600D02*
X182700Y150200D01*
G01X181617Y150774D02*
X184401Y154154D01*
G01X185900Y155200D02*
X185500Y153600D01*
G01X184401Y154154D02*
X184736Y155492D01*
G01X186033Y156643D02*
X185925Y155297D01*
G01X184736Y155492D02*
X184823Y156575D01*
G01X185709Y158305D02*
X186033Y156643D01*
G01X184531Y158075D02*
X184435Y158566D01*
G01X184823Y156575D02*
X184531Y158075D01*
G01X185661Y158551D02*
X185709Y158305D01*
G01X184531Y158075D02*
X184435Y158566D01*
G01X184823Y156575D02*
X184531Y158075D01*
G01X185613Y158795D02*
X185661Y158551D01*
G01X184435Y158566D02*
X184430Y158589D01*
G01X184531Y158075D02*
X184435Y158566D01*
G01X177263Y175666D02*
X185627Y158846D01*
G01X184404Y158608D02*
X176134Y175240D01*
G01X176416Y182868D02*
X177263Y175666D01*
G01X176085Y175404D02*
X175224Y182728D01*
G01X179668Y231285D02*
X179667D01*
G01X180204Y232359D02*
X180651Y232135D01*
G01X180114Y231061D02*
X179668Y231285D01*
G01X180204Y232359D02*
X180651Y232135D01*
G01X180203Y232359D02*
X180204D01*
G01X180777Y230151D02*
G03X180114Y231061I-1211J-186D01*
G01X180651Y232135D02*
G02X181964Y230333I-1085J-2170D01*
G01X181064Y228272D02*
X180777Y230151D01*
G01X181964Y230333D02*
X182251Y228453D01*
G01X180972Y226491D02*
G03X181064Y228272I-4281J1114D01*
G01X182251Y228453D02*
G02X182171Y226340I-5559J-848D01*
G01X180900Y219646D02*
X180972Y226491D01*
G01X182171Y226340D02*
X182100Y219617D01*
G01X180848Y218281D02*
X180900Y219646D01*
G01X182100Y219600D02*
X182043Y218122D01*
G01X180491Y216732D02*
X180848Y218281D01*
G01X182043Y218122D02*
X181600Y216200D01*
G01X179944Y216040D02*
X180491Y216732D01*
G01X181600Y216200D02*
X180100Y214300D01*
G01X179129Y215008D02*
X179944Y216040D01*
G01X181600Y216200D02*
X180100Y214300D01*
G01X177436Y212165D02*
X179091Y214953D01*
G01X180100Y214300D02*
X178468Y211552D01*
G01X176944Y210723D02*
G02X177436Y212165I3673J-448D01*
G01X178468Y211552D02*
G03X178136Y210578I2150J-1276D01*
G01X175947Y202538D02*
X176944Y210723D01*
G01X178136Y210578D02*
X177139Y202392D01*
G01X175115Y198529D02*
X175912Y202325D01*
G01X177087Y202077D02*
X176290Y198282D01*
G01X175037Y197726D02*
G02X175115Y198529I3700J46D01*
G01X176290Y198282D02*
G03X176237Y197740I2447J-513D01*
G01X175199Y183120D02*
X175037Y197726D01*
G01X176237Y197740D02*
X176399Y183133D01*
G01X175224Y182728D02*
G02X175199Y183120I3675J431D01*
G01X176399Y183133D02*
G03X176416Y182868I2500J27D01*
G01X176399Y183133D02*
G03X176416Y182868I2500J27D01*
G01X175224Y182728D02*
G02X175199Y183120I3675J431D01*
G01X176237Y197740D02*
X176399Y183133D01*
G01X175199Y183120D02*
X175037Y197726D01*
G01X176290Y198282D02*
G03X176237Y197740I2447J-513D01*
G01X175037Y197726D02*
G02X175115Y198529I3700J46D01*
G01X177087Y202077D02*
X176290Y198282D01*
G01X175115Y198529D02*
X175912Y202325D01*
G01X178136Y210578D02*
X177139Y202392D01*
G01X175947Y202538D02*
X176944Y210723D01*
G01X178468Y211552D02*
G03X178136Y210578I2150J-1276D01*
G01X176944Y210723D02*
G02X177436Y212165I3673J-448D01*
G01X180100Y214300D02*
X178468Y211552D01*
G01X177436Y212165D02*
X179091Y214953D01*
G01X181600Y216200D02*
X180100Y214300D01*
G01X179944Y216040D02*
X180491Y216732D01*
G01X179129Y215008D02*
X179944Y216040D01*
G01X182043Y218122D02*
X181600Y216200D01*
G01X180491Y216732D02*
X180848Y218281D01*
G01X182100Y219600D02*
X182043Y218122D01*
G01X180848Y218281D02*
X180900Y219646D01*
G01X182171Y226340D02*
X182100Y219617D01*
G01X180900Y219646D02*
X180972Y226491D01*
G01X182251Y228453D02*
G02X182171Y226340I-5559J-848D01*
G01X180972Y226491D02*
G03X181064Y228272I-4281J1114D01*
G01X181964Y230333D02*
X182251Y228453D01*
G01X181064Y228272D02*
X180777Y230151D01*
G01X180651Y232135D02*
G02X181964Y230333I-1085J-2170D01*
G01X180777Y230151D02*
G03X180114Y231061I-1211J-186D01*
G01X180204Y232359D02*
X180651Y232135D01*
G01X179668Y231285D02*
X179667D01*
G01X180114Y231061D02*
X179668Y231285D01*
G01X180203Y232359D02*
X180204D01*
G01X180114Y231061D02*
X179668Y231285D01*
G01X175080Y563228D02*
X173111Y565196D01*
G01X175080Y534488D02*
Y563228D01*
G01Y534488D02*
G03X175867Y533700I787J-1D01*
G01X209529D02*
X175867D01*
G01X189214Y-73346D02*
X403466D01*
G01X187245Y-71378D02*
X189214Y-73346D01*
G01X187245Y-52874D02*
Y-71378D01*
G01X254361Y-55337D02*
Y-57151D01*
G01X255561Y-55451D02*
Y-57172D01*
G01X255930Y-47129D02*
X254361Y-55337D01*
G01X257100Y-47400D02*
X255561Y-55451D01*
G01X289376Y75241D02*
X255942Y-47084D01*
G01X257495Y-45953D02*
X257100Y-47400D01*
G01X258650Y-41728D02*
X258255Y-43175D01*
G01X290479Y74723D02*
X259410Y-38950D01*
G01X263810Y-53073D02*
Y-57111D01*
G01X265010Y-53178D02*
Y-57192D01*
G01X264195Y-50885D02*
X263810Y-53073D01*
G01X265331Y-51355D02*
X265010Y-53178D01*
G01X294051Y72974D02*
X264544Y-49490D01*
G01X266752Y-45453D02*
X266401Y-46911D01*
G01X255561Y-55451D02*
Y-57172D01*
G01X254361Y-55337D02*
Y-57151D01*
G01X257100Y-47400D02*
X255561Y-55451D01*
G01X255930Y-47129D02*
X254361Y-55337D01*
G01X257495Y-45953D02*
X257100Y-47400D01*
G01X289376Y75241D02*
X255942Y-47084D01*
G01X258650Y-41728D02*
X258255Y-43175D01*
G01X289376Y75241D02*
X255942Y-47084D01*
G01X290479Y74723D02*
X259410Y-38950D01*
G01X289376Y75241D02*
X255942Y-47084D01*
G01X265010Y-53178D02*
Y-57192D01*
G01X263810Y-53073D02*
Y-57111D01*
G01X265331Y-51355D02*
X265010Y-53178D01*
G01X264195Y-50885D02*
X263810Y-53073D01*
G01X266752Y-45453D02*
X266401Y-46911D01*
G01X294051Y72974D02*
X264544Y-49490D01*
G01X294051Y72974D02*
X264544Y-49490D01*
G01X235464Y-56284D02*
Y-57146D01*
G01X236664Y-56330D02*
Y-57175D01*
G01X235803Y-51810D02*
X235464Y-56284D01*
G01X237000Y-51900D02*
X236664Y-56330D01*
G01X235814Y-51659D02*
X235803Y-51810D01*
G01X237000Y-51900D02*
X236664Y-56330D01*
G01X236293Y-50237D02*
X235814Y-51659D01*
G01X288800Y101900D02*
X237000Y-51900D01*
G01X237691Y-46087D02*
X237212Y-47508D01*
G01X288800Y101900D02*
X237000Y-51900D01*
G01X287665Y102292D02*
X238610Y-43357D01*
G01X288800Y101900D02*
X237000Y-51900D01*
G01X244912Y-53323D02*
Y-57400D01*
G01X246112Y-57023D02*
Y-53500D01*
G01X245861Y-50170D02*
X244912Y-53323D01*
G01X246112Y-53500D02*
X284654Y74534D01*
G01X247124Y-45976D02*
X246691Y-47412D01*
G01X246112Y-53500D02*
X284654Y74534D01*
G01X283520Y74933D02*
X247954Y-43218D01*
G01X246112Y-53500D02*
X284654Y74534D01*
G01X198613Y-40554D02*
X224073Y127936D01*
G01X198400Y-50000D02*
X225273Y127845D01*
G01X197959Y-44885D02*
X198183Y-43402D01*
G01X198400Y-50000D02*
X225273Y127845D01*
G01X197213Y-49821D02*
X197529Y-47732D01*
G01X198400Y-50000D02*
X225273Y127845D01*
G01X197192Y-49958D02*
X197213Y-49821D01*
G01X198400Y-50000D02*
X225273Y127845D01*
G01X197668Y-55799D02*
X197192Y-49958D01*
G01X198868Y-55750D02*
X198400Y-50000D01*
G01X197668Y-56955D02*
Y-55799D01*
G01X198868Y-56950D02*
Y-55750D01*
G01X207188Y-56298D02*
X207119Y-57207D01*
G01X208316Y-57297D02*
X208407Y-56099D01*
G01X206715Y-55181D02*
X207188Y-56298D01*
G01X208407Y-56099D02*
X207900Y-54900D01*
G01X206372Y-49949D02*
X206715Y-55181D01*
G01X207900Y-54900D02*
X207580Y-50021D01*
G01X206400Y-49800D02*
X206372Y-49949D01*
G01X207580Y-50021D02*
X240999Y128283D01*
G01X206701Y-48193D02*
X206400Y-49800D01*
G01X207580Y-50021D02*
X240999Y128283D01*
G01X207508Y-43888D02*
X207232Y-45363D01*
G01X207580Y-50021D02*
X240999Y128283D01*
G01X239800Y128400D02*
X208039Y-41057D01*
G01X207580Y-50021D02*
X240999Y128283D01*
G01X216685Y-55610D02*
X216568Y-57154D01*
G01X217765Y-57246D02*
X218009Y-54004D01*
G01X216805Y-54005D02*
X216684Y-55600D01*
G01X217765Y-57246D02*
X218009Y-54004D01*
G01X216587Y-51193D02*
X216805Y-54005D01*
G01X218009Y-54004D02*
X217800Y-51300D01*
G01X216964Y-49741D02*
X216587Y-51193D01*
G01X217800Y-51300D02*
X263568Y124785D01*
G01X218066Y-45502D02*
X217689Y-46954D01*
G01X217800Y-51300D02*
X263568Y124785D01*
G01X262400Y125064D02*
X218791Y-42715D01*
G01X217800Y-51300D02*
X263568Y124785D01*
G01X225589Y-55144D02*
X225996Y-56477D01*
G01X226800Y-55000D02*
X227144Y-56127D01*
G01X225702Y-53229D02*
X225589Y-55144D01*
G01X227000Y-51600D02*
X226800Y-55000D01*
G01X225810Y-51391D02*
X225702Y-53229D01*
G01X227000Y-51600D02*
X226800Y-55000D01*
G01X226481Y-49136D02*
X225810Y-51391D01*
G01X280000Y126500D02*
X227000Y-51600D01*
G01X227730Y-44938D02*
X227303Y-46375D01*
G01X280000Y126500D02*
X227000Y-51600D01*
G01X278828Y126772D02*
X228552Y-42177D01*
G01X280000Y126500D02*
X227000Y-51600D01*
G01X236664Y-56330D02*
Y-57175D01*
G01X235464Y-56284D02*
Y-57146D01*
G01X237000Y-51900D02*
X236664Y-56330D01*
G01X235803Y-51810D02*
X235464Y-56284D01*
G01X235814Y-51659D02*
X235803Y-51810D01*
G01X288800Y101900D02*
X237000Y-51900D01*
G01X236293Y-50237D02*
X235814Y-51659D01*
G01X237691Y-46087D02*
X237212Y-47508D01*
G01X287665Y102292D02*
X238610Y-43357D01*
G01X246112Y-53500D02*
X284654Y74534D01*
G01X245861Y-50170D02*
X244912Y-53323D01*
G01X247124Y-45976D02*
X246691Y-47412D01*
G01X283520Y74933D02*
X247954Y-43218D01*
G01X246112Y-57023D02*
Y-53500D01*
G01X244912Y-53323D02*
Y-57400D01*
G01X198400Y-50000D02*
X225273Y127845D01*
G01X198613Y-40554D02*
X224073Y127936D01*
G01X197959Y-44885D02*
X198183Y-43402D01*
G01X197213Y-49821D02*
X197529Y-47732D01*
G01X197192Y-49958D02*
X197213Y-49821D01*
G01X198868Y-55750D02*
X198400Y-50000D01*
G01X197668Y-55799D02*
X197192Y-49958D01*
G01X198868Y-56950D02*
Y-55750D01*
G01X197668Y-56955D02*
Y-55799D01*
G01X207580Y-50021D02*
X240999Y128283D01*
G01X206400Y-49800D02*
X206372Y-49949D01*
G01X206701Y-48193D02*
X206400Y-49800D01*
G01X207508Y-43888D02*
X207232Y-45363D01*
G01X239800Y128400D02*
X208039Y-41057D01*
G01X207900Y-54900D02*
X207580Y-50021D01*
G01X206372Y-49949D02*
X206715Y-55181D01*
G01X208407Y-56099D02*
X207900Y-54900D01*
G01X206715Y-55181D02*
X207188Y-56298D01*
G01X208316Y-57297D02*
X208407Y-56099D01*
G01X207188Y-56298D02*
X207119Y-57207D01*
G01X217800Y-51300D02*
X263568Y124785D01*
G01X216964Y-49741D02*
X216587Y-51193D01*
G01X218066Y-45502D02*
X217689Y-46954D01*
G01X262400Y125064D02*
X218791Y-42715D01*
G01X218009Y-54004D02*
X217800Y-51300D01*
G01X216587Y-51193D02*
X216805Y-54005D01*
G01X217765Y-57246D02*
X218009Y-54004D01*
G01X216685Y-55610D02*
X216568Y-57154D01*
G01X216805Y-54005D02*
X216684Y-55600D01*
G01X226800Y-55000D02*
X227144Y-56127D01*
G01X225589Y-55144D02*
X225996Y-56477D01*
G01X227000Y-51600D02*
X226800Y-55000D01*
G01X225702Y-53229D02*
X225589Y-55144D01*
G01X225810Y-51391D02*
X225702Y-53229D01*
G01X280000Y126500D02*
X227000Y-51600D01*
G01X226481Y-49136D02*
X225810Y-51391D01*
G01X227730Y-44938D02*
X227303Y-46375D01*
G01X278828Y126772D02*
X228552Y-42177D01*
G01X205122Y88631D02*
X187641Y-370D01*
G01X188800Y-700D02*
X206300Y88400D01*
G01X205122Y88631D02*
X187641Y-370D01*
G01X188800Y-700D02*
X206300Y88400D01*
G01X205122Y88631D02*
X187641Y-370D01*
G01X194380Y78798D02*
X188394Y111722D01*
G01X189600Y111800D02*
X195600Y78800D01*
G01X206300Y88400D02*
X206312Y88463D01*
G01X208234Y124439D02*
X205122Y88631D01*
G01X206312Y88463D02*
X209430Y124336D01*
G01X189600Y111800D02*
X195600Y78800D01*
G01X194380Y78798D02*
X188394Y111722D01*
G01X206312Y88463D02*
X209430Y124336D01*
G01X208234Y124439D02*
X205122Y88631D01*
G01X206300Y88400D02*
X206312Y88463D01*
G01X226904Y151383D02*
X226903D01*
G01X227888Y152234D02*
X227447Y152454D01*
G01X227352Y151160D02*
X226904Y151383D01*
G01X227442Y152456D02*
X227441D01*
G01X227888Y152234D02*
X227447Y152454D01*
G01X228449Y149082D02*
G03X227352Y151160I-2001J272D01*
G01X229638Y148919D02*
G03X227888Y152234I-3190J436D01*
G01X228314Y145560D02*
G02X228449Y149082I17993J1074D01*
G01X229512Y145631D02*
G02X229638Y148919I16795J1003D01*
G01X227946Y137806D02*
G03X228314Y145560I-36045J5596D01*
G01X229132Y137622D02*
G03X229512Y145631I-37231J5780D01*
G01X226230Y135232D02*
G03X227946Y137806I-1918J3138D01*
G01X226856Y134208D02*
G03X229132Y137622I-2544J4162D01*
G01X224053Y130616D02*
G02X226230Y135232I4599J652D01*
G01X225242Y130785D02*
G02X226856Y134208I3410J484D01*
G01X239819Y130514D02*
X239800Y128400D01*
G01X240999Y128283D02*
X241020Y130607D01*
G01X241979Y135231D02*
G03X239819Y130514I2423J-3963D01*
G01X241004Y130709D02*
G02X242606Y134208I3399J560D01*
G01X243696Y137806D02*
G02X241980Y135232I-3634J564D01*
G01X242606Y134208D02*
G03X244882Y137622I-2544J4162D01*
G01X244064Y145560D02*
G02X243696Y137806I-36413J-2158D01*
G01X244882Y137622D02*
G03X245262Y145631I-37231J5780D01*
G01X244199Y149082D02*
G03X244064Y145560I17858J-2448D01*
G01X245262Y145631D02*
G02X245388Y148919I16795J1003D01*
G01X243102Y151160D02*
G02X244199Y149082I-904J-1806D01*
G01X245388Y148919D02*
G03X243638Y152234I-3190J436D01*
G01X242654Y151383D02*
X243102Y151160D01*
G01X243192Y152456D02*
X243191D01*
G01X243638Y152234D02*
X243197Y152454D01*
G01X242653Y151383D02*
X242654D01*
G01X243638Y152234D02*
X243197Y152454D01*
G01X263641Y130753D02*
X262400Y125064D01*
G01X263568Y124785D02*
X264841Y130623D01*
G01X263641Y131292D02*
Y130753D01*
G01X264841Y130623D02*
Y131279D01*
G01X265090Y134699D02*
G03X263641Y131292I3507J-3503D01*
G01X264841Y131279D02*
G02X265940Y133850I3755J-85D01*
G01X266797Y136406D02*
X265090Y134699D01*
G01X265940Y133850D02*
X267646Y135557D01*
G01X267301Y137622D02*
G02X266797Y136406I-1720J0D01*
G01X266722Y151160D02*
G02X267819Y149082I-904J-1806D01*
G01X266274Y151383D02*
X266722Y151160D01*
G01X266812Y152456D02*
X266811D01*
G01X267258Y152234D02*
X266817Y152454D01*
G01X266273Y151383D02*
X266274D01*
G01X267258Y152234D02*
X266817Y152454D01*
G01X227442Y152456D02*
X227441D01*
G01X227352Y151160D02*
X226904Y151383D01*
G01X227888Y152234D02*
X227447Y152454D01*
G01X226904Y151383D02*
X226903D01*
G01X227352Y151160D02*
X226904Y151383D01*
G01X229638Y148919D02*
G03X227888Y152234I-3190J436D01*
G01X228449Y149082D02*
G03X227352Y151160I-2001J272D01*
G01X229512Y145631D02*
G02X229638Y148919I16795J1003D01*
G01X228314Y145560D02*
G02X228449Y149082I17993J1074D01*
G01X229132Y137622D02*
G03X229512Y145631I-37231J5780D01*
G01X227946Y137806D02*
G03X228314Y145560I-36045J5596D01*
G01X226856Y134208D02*
G03X229132Y137622I-2544J4162D01*
G01X226230Y135232D02*
G03X227946Y137806I-1918J3138D01*
G01X225242Y130785D02*
G02X226856Y134208I3410J484D01*
G01X224053Y130616D02*
G02X226230Y135232I4599J652D01*
G01X243192Y152456D02*
X243191D01*
G01X242654Y151383D02*
X243102Y151160D01*
G01X243638Y152234D02*
X243197Y152454D01*
G01X242654Y151383D02*
X243102Y151160D01*
G01X242653Y151383D02*
X242654D01*
G01X245388Y148919D02*
G03X243638Y152234I-3190J436D01*
G01X243102Y151160D02*
G02X244199Y149082I-904J-1806D01*
G01X245262Y145631D02*
G02X245388Y148919I16795J1003D01*
G01X244199Y149082D02*
G03X244064Y145560I17858J-2448D01*
G01X244882Y137622D02*
G03X245262Y145631I-37231J5780D01*
G01X244064Y145560D02*
G02X243696Y137806I-36413J-2158D01*
G01X242606Y134208D02*
G03X244882Y137622I-2544J4162D01*
G01X243696Y137806D02*
G02X241980Y135232I-3634J564D01*
G01X241004Y130709D02*
G02X242606Y134208I3399J560D01*
G01X241979Y135231D02*
G03X239819Y130514I2423J-3963D01*
G01X240999Y128283D02*
X241020Y130607D01*
G01X239819Y130514D02*
X239800Y128400D01*
G01X266812Y152456D02*
X266811D01*
G01X266274Y151383D02*
X266722Y151160D01*
G01X267258Y152234D02*
X266817Y152454D01*
G01X266274Y151383D02*
X266722Y151160D01*
G01X266273Y151383D02*
X266274D01*
G01X266722Y151160D02*
G02X267819Y149082I-904J-1806D01*
G01X267301Y137622D02*
G02X266797Y136406I-1720J0D01*
G01X265940Y133850D02*
X267646Y135557D01*
G01X266797Y136406D02*
X265090Y134699D01*
G01X264841Y131279D02*
G02X265940Y133850I3755J-85D01*
G01X265090Y134699D02*
G03X263641Y131292I3507J-3503D01*
G01X264841Y130623D02*
Y131279D01*
G01X263641Y131292D02*
Y130753D01*
G01X263568Y124785D02*
X264841Y130623D01*
G01X263641Y130753D02*
X262400Y125064D01*
G01X190583Y152458D02*
X190584D01*
G01X191121Y151385D02*
X190673Y151161D01*
G01X190136Y152235D02*
X190583Y152458D01*
G01X191121Y151385D02*
X190673Y151161D01*
G01X191122Y151385D02*
X191121D01*
G01X188702Y150520D02*
G02X190136Y152235I2686J-789D01*
G01X190673Y151161D02*
G03X189854Y150182I715J-1430D01*
G01X188773Y146793D02*
G02X188702Y150520I5898J1977D01*
G01X189854Y150182D02*
G03X189911Y147174I4817J-1413D01*
G01X189016Y143089D02*
G03X188773Y146793I-7152J1391D01*
G01X189911Y147174D02*
G02X190194Y142860I-8047J-2694D01*
G01X188770Y138969D02*
G02X189016Y143089I15592J1136D01*
G01X190194Y142860D02*
G03X189967Y139056I14168J-2754D01*
G01X190107Y134449D02*
G02X188770Y138969I9677J5320D01*
G01X189967Y139056D02*
G03X191159Y135027I9817J713D01*
G01X191980Y132430D02*
G02X190107Y134449I3092J4747D01*
G01X191159Y135027D02*
G03X192725Y133379I3913J2150D01*
G01X192740Y130595D02*
G03X191980Y132430I-2595J0D01*
G01X192725Y133379D02*
G02X193940Y130594I-2580J-2783D01*
G01X191902Y127388D02*
X192737Y129154D01*
G01X193937Y128885D02*
X193000Y126900D01*
G01X188812Y119969D02*
X191902Y127388D01*
G01X193000Y126900D02*
X190000Y119700D01*
G01X188394Y111722D02*
X188812Y119969D01*
G01X190000Y119700D02*
X189600Y111800D01*
G01X208591Y128631D02*
X208234Y124439D01*
G01X209430Y124336D02*
X209800Y128685D01*
G01X208323Y130151D02*
X208591Y128631D01*
G01X209800Y128685D02*
X209519Y130283D01*
G01X208297Y130729D02*
X208323Y130151D01*
G01X209519Y130283D02*
X209496Y130784D01*
G01X210485Y135232D02*
G03X208294Y130731I2422J-3963D01*
G01X209486Y130870D02*
G02X211111Y134208I3421J399D01*
G01X209497Y130786D02*
G02X209486Y130870I3410J489D01*
G01X212201Y137806D02*
G02X210485Y135232I-3634J564D01*
G01X211111Y134208D02*
G03X213387Y137622I-2544J4162D01*
G01X212569Y145560D02*
G02X212201Y137806I-36413J-2158D01*
G01X213387Y137622D02*
G03X213767Y145631I-37231J5780D01*
G01X212704Y149082D02*
G03X212569Y145560I17858J-2448D01*
G01X213767Y145631D02*
G02X213893Y148919I16795J1003D01*
G01X211607Y151160D02*
G02X212704Y149082I-904J-1806D01*
G01X213893Y148919D02*
G03X212143Y152234I-3190J436D01*
G01X211159Y151383D02*
X211607Y151160D01*
G01X211697Y152456D02*
X211696D01*
G01X212143Y152234D02*
X211702Y152454D01*
G01X211158Y151383D02*
X211159D01*
G01X212143Y152234D02*
X211702Y152454D01*
G01X190000Y119700D02*
X189600Y111800D01*
G01X188394Y111722D02*
X188812Y119969D01*
G01X193000Y126900D02*
X190000Y119700D01*
G01X188812Y119969D02*
X191902Y127388D01*
G01X193937Y128885D02*
X193000Y126900D01*
G01X191902Y127388D02*
X192737Y129154D01*
G01X192725Y133379D02*
G02X193940Y130594I-2580J-2783D01*
G01X192740Y130595D02*
G03X191980Y132430I-2595J0D01*
G01X191159Y135027D02*
G03X192725Y133379I3913J2150D01*
G01X191980Y132430D02*
G02X190107Y134449I3092J4747D01*
G01X189967Y139056D02*
G03X191159Y135027I9817J713D01*
G01X190107Y134449D02*
G02X188770Y138969I9677J5320D01*
G01X190194Y142860D02*
G03X189967Y139056I14168J-2754D01*
G01X188770Y138969D02*
G02X189016Y143089I15592J1136D01*
G01X189911Y147174D02*
G02X190194Y142860I-8047J-2694D01*
G01X189016Y143089D02*
G03X188773Y146793I-7152J1391D01*
G01X189854Y150182D02*
G03X189911Y147174I4817J-1413D01*
G01X188773Y146793D02*
G02X188702Y150520I5898J1977D01*
G01X190673Y151161D02*
G03X189854Y150182I715J-1430D01*
G01X188702Y150520D02*
G02X190136Y152235I2686J-789D01*
G01X191121Y151385D02*
X190673Y151161D01*
G01X190583Y152458D02*
X190584D01*
G01X190136Y152235D02*
X190583Y152458D01*
G01X191122Y151385D02*
X191121D01*
G01X190136Y152235D02*
X190583Y152458D01*
G01X211697Y152456D02*
X211696D01*
G01X211159Y151383D02*
X211607Y151160D01*
G01X212143Y152234D02*
X211702Y152454D01*
G01X211159Y151383D02*
X211607Y151160D01*
G01X211158Y151383D02*
X211159D01*
G01X213893Y148919D02*
G03X212143Y152234I-3190J436D01*
G01X211607Y151160D02*
G02X212704Y149082I-904J-1806D01*
G01X213767Y145631D02*
G02X213893Y148919I16795J1003D01*
G01X212704Y149082D02*
G03X212569Y145560I17858J-2448D01*
G01X213387Y137622D02*
G03X213767Y145631I-37231J5780D01*
G01X212569Y145560D02*
G02X212201Y137806I-36413J-2158D01*
G01X211111Y134208D02*
G03X213387Y137622I-2544J4162D01*
G01X212201Y137806D02*
G02X210485Y135232I-3634J564D01*
G01X209486Y130870D02*
G02X211111Y134208I3421J399D01*
G01X210485Y135232D02*
G03X208294Y130731I2422J-3963D01*
G01X209497Y130786D02*
G02X209486Y130870I3410J489D01*
G01X210485Y135232D02*
G03X208294Y130731I2422J-3963D01*
G01X209519Y130283D02*
X209496Y130784D01*
G01X208297Y130729D02*
X208323Y130151D01*
G01X209800Y128685D02*
X209519Y130283D01*
G01X208323Y130151D02*
X208591Y128631D01*
G01X209430Y124336D02*
X209800Y128685D01*
G01X208591Y128631D02*
X208234Y124439D01*
G01X209529Y533700D02*
G03X210316Y534488I0J787D01*
G01Y563228D02*
Y534488D01*
G01X212284Y565196D02*
X210316Y563228D01*
G01X426536Y565196D02*
X212284D01*
G01X346894Y-47902D02*
X348388Y-54448D01*
G01X346849Y-47567D02*
X346894Y-47902D01*
G01X347042Y-43429D02*
X346849Y-47567D01*
G01X347042Y-38879D02*
Y-43429D01*
G01X346894Y-47902D02*
X348388Y-54448D01*
G01X346849Y-47567D02*
X346894Y-47902D01*
G01X347042Y-43429D02*
X346849Y-47567D01*
G01X347042Y-38879D02*
Y-43429D01*
G01X336842Y-42061D02*
Y-38879D01*
G01X338042D02*
Y-42166D01*
G01X336497Y-44034D02*
X336842Y-42061D01*
G01X338042Y-42166D02*
X337708Y-44078D01*
G01X336737Y-46406D02*
X336497Y-44034D01*
G01X337708Y-44078D02*
X337931Y-46284D01*
G01X336955Y-48515D02*
X336737Y-46406D01*
G01X337931Y-46284D02*
X338137Y-48272D01*
G01X339399Y-56327D02*
X336955Y-48515D01*
G01X338137Y-48272D02*
X340545Y-55970D01*
G01X339400Y-57211D02*
Y-56330D01*
G01X340600Y-56146D02*
Y-57111D01*
G01X329952Y-56330D02*
Y-57058D01*
G01X331152Y-56100D02*
Y-57263D01*
G01X327600Y-50400D02*
X329952Y-56330D01*
G01X328721Y-49971D02*
X331152Y-56100D01*
G01X326699Y-47960D02*
X327600Y-50400D01*
G01X327831Y-47559D02*
X328721Y-49971D01*
G01X326511Y-46475D02*
G03X326699Y-47960I3689J-287D01*
G01X327708Y-46569D02*
G03X327831Y-47559I2492J-193D01*
G01X326603Y-45318D02*
X326511Y-46475D01*
G01X327803Y-45372D02*
X327708Y-46569D01*
G01X326642Y-38879D02*
Y-41754D01*
G01X327842Y-38879D02*
Y-41761D01*
G01X340600Y-56146D02*
Y-57111D01*
G01X339400Y-57211D02*
Y-56330D01*
G01X338137Y-48272D02*
X340545Y-55970D01*
G01X339399Y-56327D02*
X336955Y-48515D01*
G01X337931Y-46284D02*
X338137Y-48272D01*
G01X336955Y-48515D02*
X336737Y-46406D01*
G01X337708Y-44078D02*
X337931Y-46284D01*
G01X336737Y-46406D02*
X336497Y-44034D01*
G01X338042Y-42166D02*
X337708Y-44078D01*
G01X336497Y-44034D02*
X336842Y-42061D01*
G01X338042Y-38879D02*
Y-42166D01*
G01X336842Y-42061D02*
Y-38879D01*
G01X331152Y-56100D02*
Y-57263D01*
G01X329952Y-56330D02*
Y-57058D01*
G01X328721Y-49971D02*
X331152Y-56100D01*
G01X327600Y-50400D02*
X329952Y-56330D01*
G01X327831Y-47559D02*
X328721Y-49971D01*
G01X326699Y-47960D02*
X327600Y-50400D01*
G01X327708Y-46569D02*
G03X327831Y-47559I2492J-193D01*
G01X326511Y-46475D02*
G03X326699Y-47960I3689J-287D01*
G01X327803Y-45372D02*
X327708Y-46569D01*
G01X326603Y-45318D02*
X326511Y-46475D01*
G01X327842Y-38879D02*
Y-41761D01*
G01X326642Y-38879D02*
Y-41754D01*
G01X273259Y-53128D02*
Y-57364D01*
G01X274459Y-53234D02*
Y-57341D01*
G01X274008Y-48882D02*
X273259Y-53128D01*
G01X275144Y-49352D02*
X274459Y-53234D01*
G01X298523Y70733D02*
X274008Y-48882D01*
G01X275445Y-47883D02*
X275144Y-49352D01*
G01X276325Y-43592D02*
X276023Y-45061D01*
G01X299659Y70263D02*
X276903Y-40770D01*
G01X282064Y-48035D02*
X302935Y68150D01*
G01X283537Y-46625D02*
X283272Y-48101D01*
G01X284312Y-42314D02*
X284046Y-43790D01*
G01X304070Y67678D02*
X284821Y-39479D01*
G01X282074Y-48183D02*
X282064Y-48035D01*
G01X283272Y-48101D02*
X283485Y-51207D01*
G01X282287Y-51290D02*
X282074Y-48183D01*
G01X283272Y-48101D02*
X283485Y-51207D01*
G01X282707Y-57372D02*
X282287Y-51290D01*
G01X283485Y-51207D02*
X283908Y-57319D01*
G01X289613Y-38331D02*
X308051Y66228D01*
G01X309187Y65758D02*
X290828Y-38356D01*
G01X292148Y-57268D02*
X289613Y-38331D01*
G01X293346Y-57179D02*
X293353Y-57235D01*
G01X292939Y-54122D02*
X293339Y-57112D01*
G01X292358Y-49780D02*
X292557Y-51267D01*
G01X290828Y-38356D02*
X291975Y-46926D01*
G01X297363Y-22807D02*
X312703Y64174D01*
G01X313839Y63704D02*
X298577Y-22838D01*
G01X301526Y-56239D02*
X297363Y-22807D01*
G01X302460Y-54027D02*
X302717Y-56089D01*
G01X301919Y-49680D02*
X302104Y-51169D01*
G01X298577Y-22838D02*
X301563Y-46822D01*
G01X301603Y-57185D02*
X301527Y-56241D01*
G01X302720Y-56091D02*
X302805Y-57087D01*
G01X310921Y-55625D02*
X311055Y-57228D01*
G01X312110Y-55433D02*
X312251Y-57129D01*
G01X302600Y-21294D02*
X310921Y-55625D01*
G01X311757Y-53975D02*
X312110Y-55433D01*
G01X310725Y-49718D02*
X311078Y-51176D01*
G01X303819Y-21228D02*
X310046Y-46920D01*
G01X302629Y-21073D02*
X302600Y-21294D01*
G01X304326Y-17358D02*
X303819Y-21228D01*
G01X303137Y-17194D02*
X302629Y-21073D01*
G01X304326Y-17358D02*
X303819Y-21228D01*
G01X303219Y-16621D02*
X303137Y-17194D01*
G01X304326Y-17358D02*
X303819Y-21228D01*
G01X304485Y-16257D02*
X304326Y-17358D01*
G01X303299Y-16067D02*
X303219Y-16621D01*
G01X304485Y-16257D02*
X304326Y-17358D01*
G01X303418Y-15392D02*
X303299Y-16067D01*
G01X304600Y-15600D02*
X304485Y-16257D01*
G01X318142Y61179D02*
X304600Y-15600D01*
G01X317006Y61649D02*
X303418Y-15392D01*
G01X304600Y-15600D02*
X304485Y-16257D01*
G01X318142Y61179D02*
X304600Y-15600D01*
G01X320503Y-55424D02*
Y-57019D01*
G01X321703Y-55319D02*
Y-57092D01*
G01X320243Y-53951D02*
X320503Y-55424D01*
G01X321379Y-53481D02*
X321703Y-55319D01*
G01X313940Y-44949D02*
X320243Y-53951D01*
G01X315076Y-44479D02*
X321379Y-53481D01*
G01X308538Y-14315D02*
X313940Y-44949D01*
G01X314816Y-43002D02*
X315076Y-44479D01*
G01X314055Y-38688D02*
X314315Y-40166D01*
G01X309757Y-14315D02*
X313555Y-35852D01*
G01X321556Y59536D02*
X308538Y-14315D01*
G01X322692Y59066D02*
X309757Y-14315D01*
G01X274459Y-53234D02*
Y-57341D01*
G01X273259Y-53128D02*
Y-57364D01*
G01X275144Y-49352D02*
X274459Y-53234D01*
G01X274008Y-48882D02*
X273259Y-53128D01*
G01X275445Y-47883D02*
X275144Y-49352D01*
G01X298523Y70733D02*
X274008Y-48882D01*
G01X276325Y-43592D02*
X276023Y-45061D01*
G01X298523Y70733D02*
X274008Y-48882D01*
G01X299659Y70263D02*
X276903Y-40770D01*
G01X298523Y70733D02*
X274008Y-48882D01*
G01X283485Y-51207D02*
X283908Y-57319D01*
G01X282707Y-57372D02*
X282287Y-51290D01*
G01X283272Y-48101D02*
X283485Y-51207D01*
G01X282074Y-48183D02*
X282064Y-48035D01*
G01X282287Y-51290D02*
X282074Y-48183D01*
G01X283537Y-46625D02*
X283272Y-48101D01*
G01X282064Y-48035D02*
X302935Y68150D01*
G01X284312Y-42314D02*
X284046Y-43790D01*
G01X282064Y-48035D02*
X302935Y68150D01*
G01X304070Y67678D02*
X284821Y-39479D01*
G01X282064Y-48035D02*
X302935Y68150D01*
G01X293346Y-57179D02*
X293353Y-57235D01*
G01X292148Y-57268D02*
X289613Y-38331D01*
G01X292939Y-54122D02*
X293339Y-57112D01*
G01X292148Y-57268D02*
X289613Y-38331D01*
G01X292358Y-49780D02*
X292557Y-51267D01*
G01X292148Y-57268D02*
X289613Y-38331D01*
G01X290828Y-38356D02*
X291975Y-46926D01*
G01X292148Y-57268D02*
X289613Y-38331D01*
G01X309187Y65758D02*
X290828Y-38356D01*
G01X289613Y-38331D02*
X308051Y66228D01*
G01X302720Y-56091D02*
X302805Y-57087D01*
G01X301603Y-57185D02*
X301527Y-56241D01*
G01X302460Y-54027D02*
X302717Y-56089D01*
G01X301526Y-56239D02*
X297363Y-22807D01*
G01X301919Y-49680D02*
X302104Y-51169D01*
G01X301526Y-56239D02*
X297363Y-22807D01*
G01X298577Y-22838D02*
X301563Y-46822D01*
G01X301526Y-56239D02*
X297363Y-22807D01*
G01X313839Y63704D02*
X298577Y-22838D01*
G01X297363Y-22807D02*
X312703Y64174D01*
G01X312110Y-55433D02*
X312251Y-57129D01*
G01X310921Y-55625D02*
X311055Y-57228D01*
G01X311757Y-53975D02*
X312110Y-55433D01*
G01X302600Y-21294D02*
X310921Y-55625D01*
G01X310725Y-49718D02*
X311078Y-51176D01*
G01X302600Y-21294D02*
X310921Y-55625D01*
G01X303819Y-21228D02*
X310046Y-46920D01*
G01X302600Y-21294D02*
X310921Y-55625D01*
G01X304326Y-17358D02*
X303819Y-21228D01*
G01X302629Y-21073D02*
X302600Y-21294D01*
G01X303137Y-17194D02*
X302629Y-21073D01*
G01X303219Y-16621D02*
X303137Y-17194D01*
G01X304485Y-16257D02*
X304326Y-17358D01*
G01X303219Y-16621D02*
X303137Y-17194D01*
G01X303299Y-16067D02*
X303219Y-16621D01*
G01X304600Y-15600D02*
X304485Y-16257D01*
G01X303418Y-15392D02*
X303299Y-16067D01*
G01X317006Y61649D02*
X303418Y-15392D01*
G01X318142Y61179D02*
X304600Y-15600D01*
G01X303418Y-15392D02*
X303299Y-16067D01*
G01X317006Y61649D02*
X303418Y-15392D01*
G01X321703Y-55319D02*
Y-57092D01*
G01X320503Y-55424D02*
Y-57019D01*
G01X321379Y-53481D02*
X321703Y-55319D01*
G01X320243Y-53951D02*
X320503Y-55424D01*
G01X315076Y-44479D02*
X321379Y-53481D01*
G01X313940Y-44949D02*
X320243Y-53951D01*
G01X314816Y-43002D02*
X315076Y-44479D01*
G01X308538Y-14315D02*
X313940Y-44949D01*
G01X314055Y-38688D02*
X314315Y-40166D01*
G01X308538Y-14315D02*
X313940Y-44949D01*
G01X309757Y-14315D02*
X313555Y-35852D01*
G01X308538Y-14315D02*
X313940Y-44949D01*
G01X322692Y59066D02*
X309757Y-14315D01*
G01X321556Y59536D02*
X308538Y-14315D01*
G01X295165Y72472D02*
X267427Y-42653D01*
G01X295165Y72472D02*
X267427Y-42653D01*
G01X330340Y116172D02*
X298523Y70733D01*
G01X331202Y115310D02*
X299659Y70263D01*
G01X302935Y68150D02*
X334754Y113592D01*
G01X335616Y112730D02*
X304070Y67678D01*
G01X308051Y66228D02*
X337550Y108359D01*
G01X338412Y107497D02*
X309187Y65758D01*
G01X312703Y64174D02*
X340200Y103444D01*
G01X341062Y102582D02*
X313839Y63704D01*
G01X344128Y100384D02*
X317006Y61649D01*
G01X344990Y99522D02*
X318142Y61179D01*
G01X352100Y104500D02*
X344990Y99522D01*
G01X346025Y94481D02*
X321556Y59536D01*
G01X346887Y93619D02*
X322692Y59066D01*
G01X346474Y94917D02*
X346040Y94482D01*
G01X346889Y93621D02*
X346887Y93619D01*
G01X347249Y93993D02*
X346889Y93633D01*
G01X353098Y99554D02*
X346474Y94917D01*
G01X353568Y98418D02*
X347249Y93993D01*
G01X331202Y115310D02*
X299659Y70263D01*
G01X330340Y116172D02*
X298523Y70733D01*
G01X335616Y112730D02*
X304070Y67678D01*
G01X302935Y68150D02*
X334754Y113592D01*
G01X338412Y107497D02*
X309187Y65758D01*
G01X308051Y66228D02*
X337550Y108359D01*
G01X341062Y102582D02*
X313839Y63704D01*
G01X312703Y64174D02*
X340200Y103444D01*
G01X344990Y99522D02*
X318142Y61179D01*
G01X344128Y100384D02*
X317006Y61649D01*
G01X352100Y104500D02*
X344990Y99522D01*
G01X346887Y93619D02*
X322692Y59066D01*
G01X346025Y94481D02*
X321556Y59536D01*
G01X346889Y93621D02*
X346887Y93619D01*
G01X346474Y94917D02*
X346040Y94482D01*
G01X347249Y93993D02*
X346889Y93633D01*
G01X346474Y94917D02*
X346040Y94482D01*
G01X353568Y98418D02*
X347249Y93993D01*
G01X353098Y99554D02*
X346474Y94917D01*
G01X289495Y75411D02*
X289376Y75241D01*
G01X313500Y107600D02*
X290479Y74723D01*
G01X312517Y108289D02*
X289496Y75411D01*
G01X313500Y107600D02*
X290479Y74723D01*
G01X309583Y95156D02*
X294051Y72974D01*
G01X328486Y120060D02*
X295165Y72472D01*
G01X327624Y120922D02*
X309583Y95156D01*
G01X328486Y120060D02*
X295165Y72472D01*
G01X313500Y107600D02*
X290479Y74723D01*
G01X289495Y75411D02*
X289376Y75241D01*
G01X312517Y108289D02*
X289496Y75411D01*
G01X328486Y120060D02*
X295165Y72472D01*
G01X309583Y95156D02*
X294051Y72974D01*
G01X327624Y120922D02*
X309583Y95156D01*
G01X284066Y76284D02*
X283520Y74933D01*
G01X285179Y75835D02*
X285270Y76061D01*
G01X284654Y74534D02*
X285179Y75835D01*
G01X284127Y76438D02*
X284066Y76284D01*
G01X285179Y75835D02*
X285270Y76061D01*
G01X284654Y74534D02*
X285179Y75835D01*
G01X284157Y76511D02*
X284127Y76438D01*
G01X285179Y75835D02*
X285270Y76061D01*
G01X310300Y127400D02*
X284157Y76517D01*
G01X285275Y76065D02*
X311465Y127041D01*
G01X285275Y76065D02*
X311465Y127041D01*
G01X310300Y127400D02*
X284157Y76517D01*
G01X285179Y75835D02*
X285270Y76061D01*
G01X284066Y76284D02*
X283520Y74933D01*
G01X284127Y76438D02*
X284066Y76284D01*
G01X284157Y76511D02*
X284127Y76438D01*
G01X284654Y74534D02*
X285179Y75835D01*
G01X284066Y76284D02*
X283520Y74933D01*
G01X284127Y76438D02*
X284066Y76284D01*
G01X331918Y117736D02*
X330355Y116173D01*
G01X331204Y115312D02*
X331202Y115310D01*
G01X331564Y115684D02*
X331204Y115324D01*
G01X332693Y116812D02*
X331564Y115683D01*
G01X340830Y123976D02*
X331918Y117736D01*
G01X341300Y122840D02*
X332693Y116812D01*
G01X346819Y125033D02*
X340830Y123976D01*
G01X347289Y123897D02*
X341300Y122840D01*
G01X349042Y126590D02*
X346819Y125033D01*
G01X343384Y119635D02*
X358241Y122253D01*
G01X358711Y121117D02*
X343854Y118499D01*
G01X334754Y113592D02*
X343384Y119635D01*
G01X343854Y118499D02*
X335616Y112730D01*
G01X346612Y114704D02*
X351592Y115582D01*
G01X351800Y114400D02*
X347082Y113568D01*
G01X337550Y108359D02*
X346612Y114704D01*
G01X347082Y113568D02*
X338412Y107497D01*
G01X340200Y103444D02*
X349860Y110208D01*
G01X350330Y109072D02*
X341062Y102582D01*
G01X351630Y105636D02*
X344128Y100384D01*
G01X331204Y115312D02*
X331202Y115310D01*
G01X331918Y117736D02*
X330355Y116173D01*
G01X331564Y115684D02*
X331204Y115324D01*
G01X331918Y117736D02*
X330355Y116173D01*
G01X332693Y116812D02*
X331564Y115683D01*
G01X331918Y117736D02*
X330355Y116173D01*
G01X341300Y122840D02*
X332693Y116812D01*
G01X340830Y123976D02*
X331918Y117736D01*
G01X347289Y123897D02*
X341300Y122840D01*
G01X346819Y125033D02*
X340830Y123976D01*
G01X349042Y126590D02*
X346819Y125033D01*
G01X349042Y126590D02*
X346819Y125033D01*
G01X343854Y118499D02*
X335616Y112730D01*
G01X334754Y113592D02*
X343384Y119635D01*
G01X358711Y121117D02*
X343854Y118499D01*
G01X343384Y119635D02*
X358241Y122253D01*
G01X347082Y113568D02*
X338412Y107497D01*
G01X337550Y108359D02*
X346612Y114704D01*
G01X351800Y114400D02*
X347082Y113568D01*
G01X346612Y114704D02*
X351592Y115582D01*
G01X350330Y109072D02*
X341062Y102582D01*
G01X340200Y103444D02*
X349860Y110208D01*
G01X351630Y105636D02*
X344128Y100384D01*
G01X315743Y112896D02*
X312517Y108289D01*
G01X316879Y112426D02*
X313500Y107600D01*
G01X318600Y129103D02*
X315743Y112896D01*
G01X319800Y128998D02*
X316879Y112426D01*
G01X318600Y130723D02*
Y129103D01*
G01X319800Y130722D02*
Y128998D01*
G01X319994Y134089D02*
G03X318600Y130723I3367J-3366D01*
G01X320843Y133240D02*
G03X319800Y130722I2518J-2518D01*
G01X321825Y135920D02*
X319994Y134089D01*
G01X322674Y135071D02*
X320843Y133240D01*
G01X322537Y137640D02*
G02X321825Y135920I-2432J0D01*
G01X323738Y137640D02*
G02X322674Y135071I-3633J0D01*
G01X322538Y139712D02*
Y137639D01*
G01X323738Y139713D02*
Y137640D01*
G01X323281Y141511D02*
G03X322538Y139712I1800J-1796D01*
G01X324131Y140662D02*
G03X323738Y139713I949J-949D01*
G01X324844Y143074D02*
X323281Y141511D01*
G01X325693Y142225D02*
X324131Y140662D01*
G01X326769Y143870D02*
G03X324844Y143074I-2J-2722D01*
G01X326769Y142670D02*
G03X325693Y142225I-1J-1521D01*
G01X330472Y147573D02*
G02X326769Y143870I-3703J0D01*
G01X331672Y147573D02*
G02X326769Y142670I-4903J0D01*
G01X330472Y149395D02*
Y147573D01*
G01X331672Y149396D02*
Y147573D01*
G01X331709Y152157D02*
G03X330472Y149395I2460J-2760D01*
G01X332403Y151161D02*
G03X331672Y149396I1765J-1765D01*
G01X332313Y152458D02*
X331709Y152157D01*
G01X332851Y151385D02*
X332403Y151161D01*
G01X332852Y151385D02*
X332851D01*
G01X332314Y152458D02*
X332313D01*
G01X332851Y151385D02*
X332403Y151161D01*
G01X332616Y124416D02*
X327624Y120922D01*
G01X333478Y123554D02*
X328486Y120060D01*
G01X333817Y126132D02*
X332616Y124416D01*
G01X334953Y125662D02*
X333478Y123554D01*
G01X334250Y128590D02*
X333817Y126132D01*
G01X335445Y128451D02*
X334953Y125662D01*
G01X334341Y130217D02*
X334250Y128590D01*
G01X335540Y130150D02*
X335445Y128451D01*
G01X334350Y130505D02*
G02X334341Y130217I-5165J17D01*
G01X335550Y130504D02*
G02X335540Y130150I-6365J3D01*
G01X334350Y130723D02*
Y130505D01*
G01X335550Y130722D02*
Y130504D01*
G01X335744Y134089D02*
G03X334350Y130723I3367J-3366D01*
G01X336593Y133240D02*
G03X335550Y130722I2518J-2518D01*
G01X337575Y135920D02*
X335744Y134089D01*
G01X338424Y135071D02*
X336593Y133240D01*
G01X338287Y137640D02*
G02X337575Y135920I-2432J0D01*
G01X339488Y137640D02*
G02X338424Y135071I-3633J0D01*
G01X338288Y139712D02*
Y137639D01*
G01X339488Y139713D02*
Y137640D01*
G01X339031Y141511D02*
G03X338288Y139712I1800J-1796D01*
G01X339881Y140662D02*
G03X339488Y139713I949J-949D01*
G01X340594Y143074D02*
X339031Y141511D01*
G01X341443Y142225D02*
X339881Y140662D01*
G01X342519Y143870D02*
G03X340594Y143074I-2J-2722D01*
G01X342519Y142670D02*
G03X341443Y142225I-1J-1521D01*
G01X346222Y147573D02*
G02X342519Y143870I-3703J0D01*
G01X347422Y147573D02*
G02X342519Y142670I-4903J0D01*
G01X346222Y149395D02*
Y147573D01*
G01X347459Y152157D02*
G03X346222Y149395I2460J-2760D01*
G01X316879Y112426D02*
X313500Y107600D01*
G01X315743Y112896D02*
X312517Y108289D01*
G01X319800Y128998D02*
X316879Y112426D01*
G01X318600Y129103D02*
X315743Y112896D01*
G01X319800Y130722D02*
Y128998D01*
G01X318600Y130723D02*
Y129103D01*
G01X320843Y133240D02*
G03X319800Y130722I2518J-2518D01*
G01X319994Y134089D02*
G03X318600Y130723I3367J-3366D01*
G01X322674Y135071D02*
X320843Y133240D01*
G01X321825Y135920D02*
X319994Y134089D01*
G01X323738Y137640D02*
G02X322674Y135071I-3633J0D01*
G01X322537Y137640D02*
G02X321825Y135920I-2432J0D01*
G01X323738Y139713D02*
Y137640D01*
G01X322538Y139712D02*
Y137639D01*
G01X324131Y140662D02*
G03X323738Y139713I949J-949D01*
G01X323281Y141511D02*
G03X322538Y139712I1800J-1796D01*
G01X325693Y142225D02*
X324131Y140662D01*
G01X324844Y143074D02*
X323281Y141511D01*
G01X326769Y142670D02*
G03X325693Y142225I-1J-1521D01*
G01X326769Y143870D02*
G03X324844Y143074I-2J-2722D01*
G01X331672Y147573D02*
G02X326769Y142670I-4903J0D01*
G01X330472Y147573D02*
G02X326769Y143870I-3703J0D01*
G01X331672Y149396D02*
Y147573D01*
G01X330472Y149395D02*
Y147573D01*
G01X332403Y151161D02*
G03X331672Y149396I1765J-1765D01*
G01X331709Y152157D02*
G03X330472Y149395I2460J-2760D01*
G01X332851Y151385D02*
X332403Y151161D01*
G01X332313Y152458D02*
X331709Y152157D01*
G01X332314Y152458D02*
X332313D01*
G01X332852Y151385D02*
X332851D01*
G01X332313Y152458D02*
X331709Y152157D01*
G01X333478Y123554D02*
X328486Y120060D01*
G01X332616Y124416D02*
X327624Y120922D01*
G01X334953Y125662D02*
X333478Y123554D01*
G01X333817Y126132D02*
X332616Y124416D01*
G01X335445Y128451D02*
X334953Y125662D01*
G01X334250Y128590D02*
X333817Y126132D01*
G01X335540Y130150D02*
X335445Y128451D01*
G01X334341Y130217D02*
X334250Y128590D01*
G01X335550Y130504D02*
G02X335540Y130150I-6365J3D01*
G01X334350Y130505D02*
G02X334341Y130217I-5165J17D01*
G01X335550Y130722D02*
Y130504D01*
G01X334350Y130723D02*
Y130505D01*
G01X336593Y133240D02*
G03X335550Y130722I2518J-2518D01*
G01X335744Y134089D02*
G03X334350Y130723I3367J-3366D01*
G01X338424Y135071D02*
X336593Y133240D01*
G01X337575Y135920D02*
X335744Y134089D01*
G01X339488Y137640D02*
G02X338424Y135071I-3633J0D01*
G01X338287Y137640D02*
G02X337575Y135920I-2432J0D01*
G01X339488Y139713D02*
Y137640D01*
G01X338288Y139712D02*
Y137639D01*
G01X339881Y140662D02*
G03X339488Y139713I949J-949D01*
G01X339031Y141511D02*
G03X338288Y139712I1800J-1796D01*
G01X341443Y142225D02*
X339881Y140662D01*
G01X340594Y143074D02*
X339031Y141511D01*
G01X342519Y142670D02*
G03X341443Y142225I-1J-1521D01*
G01X342519Y143870D02*
G03X340594Y143074I-2J-2722D01*
G01X347422Y147573D02*
G02X342519Y142670I-4903J0D01*
G01X346222Y147573D02*
G02X342519Y143870I-3703J0D01*
G01X346222Y149395D02*
Y147573D01*
G01X347459Y152157D02*
G03X346222Y149395I2460J-2760D01*
G01X295043Y129017D02*
X287665Y102292D01*
G01X296255Y128897D02*
X288811Y101931D01*
G01X294972Y130008D02*
X295043Y129017D01*
G01X296178Y129971D02*
X296255Y128897D01*
G01X296134Y130593D02*
X296178Y129971D01*
G01X294936Y130508D02*
X294972Y130008D01*
G01X296178Y129971D02*
X296255Y128897D01*
G01X296134Y130593D02*
X296178Y129971D01*
G01X297095Y135232D02*
G03X294934Y130514I2422J-3963D01*
G01X297721Y134208D02*
G03X296119Y130709I1797J-2939D01*
G01X298811Y137806D02*
G02X297095Y135232I-3634J564D01*
G01X299997Y137622D02*
G02X297721Y134208I-4820J748D01*
G01X299179Y145560D02*
G02X298811Y137806I-36413J-2158D01*
G01X300377Y145631D02*
G02X299997Y137622I-37611J-2229D01*
G01X299314Y149082D02*
G03X299179Y145560I17858J-2448D01*
G01X300503Y148919D02*
G03X300377Y145631I16669J-2285D01*
G01X298217Y151160D02*
G02X299314Y149082I-904J-1806D01*
G01X298753Y152234D02*
G02X300503Y148919I-1440J-2879D01*
G01X297777Y151379D02*
X298217Y151160D01*
G01X298312Y152454D02*
X298753Y152234D01*
G01X298306Y152456D02*
X298307D01*
G01X297769Y151383D02*
X297777Y151379D01*
G01X298312Y152454D02*
X298753Y152234D01*
G01X297768Y151383D02*
X297769D01*
G01X298312Y152454D02*
X298753Y152234D01*
G01X310684Y130513D02*
X310300Y127400D01*
G01X311491Y127253D02*
X311897Y130538D01*
G01X311465Y127041D02*
X311491Y127253D01*
G01X312845Y135232D02*
G03X310684Y130513I2422J-3963D01*
G01X311869Y130708D02*
G02X313471Y134208I3398J561D01*
G01X314561Y137806D02*
G02X312845Y135232I-3634J564D01*
G01X313471Y134208D02*
G03X315747Y137622I-2544J4162D01*
G01X314929Y145560D02*
G02X314561Y137806I-36413J-2158D01*
G01X315747Y137622D02*
G03X316127Y145631I-37231J5780D01*
G01X315064Y149082D02*
G03X314929Y145560I17858J-2448D01*
G01X316127Y145631D02*
G02X316253Y148919I16795J1003D01*
G01X313967Y151160D02*
G02X315064Y149082I-904J-1806D01*
G01X316253Y148919D02*
G03X314503Y152234I-3190J436D01*
G01X313519Y151383D02*
X313967Y151160D01*
G01X314057Y152456D02*
X314056D01*
G01X314503Y152234D02*
X314062Y152454D01*
G01X313518Y151383D02*
X313519D01*
G01X314503Y152234D02*
X314062Y152454D01*
G01X267646Y135557D02*
G03X268502Y137622I-2065J2066D01*
G01X267299Y137704D02*
G02X267301Y137622I-1718J-83D01*
G01X267646Y135557D02*
G03X268502Y137622I-2065J2066D01*
G01X267684Y145560D02*
G02X267299Y137704I-36412J-2153D01*
G01X268502Y137622D02*
G03X268882Y145631I-37231J5780D01*
G01X267819Y149082D02*
G03X267684Y145560I17858J-2448D01*
G01X268882Y145631D02*
G02X269008Y148919I16795J1003D01*
G01D02*
G03X267258Y152234I-3190J436D01*
G01X279390Y130095D02*
X278828Y126772D01*
G01X280590Y129994D02*
X280000Y126500D01*
G01X279390Y131194D02*
Y130095D01*
G01X280590Y131194D02*
Y129994D01*
G01X280840Y134699D02*
G03X279390Y131194I3507J-3503D01*
G01X281690Y133850D02*
G03X280590Y131194I2656J-2656D01*
G01X282547Y136406D02*
X280840Y134699D01*
G01X283396Y135557D02*
X281690Y133850D01*
G01X283051Y137622D02*
G02X282547Y136406I-1720J0D01*
G01X284252Y137622D02*
G02X283396Y135557I-2921J1D01*
G01X283049Y137704D02*
G02X283051Y137622I-1718J-83D01*
G01X284252D02*
G02X283396Y135557I-2921J1D01*
G01X283434Y145560D02*
G02X283049Y137704I-36412J-2153D01*
G01X284632Y145631D02*
G02X284252Y137622I-37611J-2229D01*
G01X283569Y149082D02*
G03X283434Y145560I17858J-2448D01*
G01X284758Y148919D02*
G03X284632Y145631I16669J-2285D01*
G01X282472Y151160D02*
G02X283569Y149082I-904J-1806D01*
G01X283008Y152234D02*
G02X284758Y148919I-1440J-2879D01*
G01X282024Y151383D02*
X282472Y151160D01*
G01X282567Y152454D02*
X283008Y152234D01*
G01X282561Y152456D02*
X282562D01*
G01X282023Y151383D02*
X282024D01*
G01X282567Y152454D02*
X283008Y152234D01*
G01X296255Y128897D02*
X288811Y101931D01*
G01X295043Y129017D02*
X287665Y102292D01*
G01X296178Y129971D02*
X296255Y128897D01*
G01X294972Y130008D02*
X295043Y129017D01*
G01X294936Y130508D02*
X294972Y130008D01*
G01X296134Y130593D02*
X296178Y129971D01*
G01X294972Y130008D02*
X295043Y129017D01*
G01X294936Y130508D02*
X294972Y130008D01*
G01X297721Y134208D02*
G03X296119Y130709I1797J-2939D01*
G01X297095Y135232D02*
G03X294934Y130514I2422J-3963D01*
G01X299997Y137622D02*
G02X297721Y134208I-4820J748D01*
G01X298811Y137806D02*
G02X297095Y135232I-3634J564D01*
G01X300377Y145631D02*
G02X299997Y137622I-37611J-2229D01*
G01X299179Y145560D02*
G02X298811Y137806I-36413J-2158D01*
G01X300503Y148919D02*
G03X300377Y145631I16669J-2285D01*
G01X299314Y149082D02*
G03X299179Y145560I17858J-2448D01*
G01X298753Y152234D02*
G02X300503Y148919I-1440J-2879D01*
G01X298217Y151160D02*
G02X299314Y149082I-904J-1806D01*
G01X298312Y152454D02*
X298753Y152234D01*
G01X297777Y151379D02*
X298217Y151160D01*
G01X297769Y151383D02*
X297777Y151379D01*
G01X297768Y151383D02*
X297769D01*
G01X298306Y152456D02*
X298307D01*
G01X297777Y151379D02*
X298217Y151160D01*
G01X314057Y152456D02*
X314056D01*
G01X313519Y151383D02*
X313967Y151160D01*
G01X314503Y152234D02*
X314062Y152454D01*
G01X313519Y151383D02*
X313967Y151160D01*
G01X313518Y151383D02*
X313519D01*
G01X316253Y148919D02*
G03X314503Y152234I-3190J436D01*
G01X313967Y151160D02*
G02X315064Y149082I-904J-1806D01*
G01X316127Y145631D02*
G02X316253Y148919I16795J1003D01*
G01X315064Y149082D02*
G03X314929Y145560I17858J-2448D01*
G01X315747Y137622D02*
G03X316127Y145631I-37231J5780D01*
G01X314929Y145560D02*
G02X314561Y137806I-36413J-2158D01*
G01X313471Y134208D02*
G03X315747Y137622I-2544J4162D01*
G01X314561Y137806D02*
G02X312845Y135232I-3634J564D01*
G01X311869Y130708D02*
G02X313471Y134208I3398J561D01*
G01X312845Y135232D02*
G03X310684Y130513I2422J-3963D01*
G01X311491Y127253D02*
X311897Y130538D01*
G01X310684Y130513D02*
X310300Y127400D01*
G01X311465Y127041D02*
X311491Y127253D01*
G01X310684Y130513D02*
X310300Y127400D01*
G01X269008Y148919D02*
G03X267258Y152234I-3190J436D01*
G01X268882Y145631D02*
G02X269008Y148919I16795J1003D01*
G01X267819Y149082D02*
G03X267684Y145560I17858J-2448D01*
G01X268502Y137622D02*
G03X268882Y145631I-37231J5780D01*
G01X267684Y145560D02*
G02X267299Y137704I-36412J-2153D01*
G01X267646Y135557D02*
G03X268502Y137622I-2065J2066D01*
G01X267299Y137704D02*
G02X267301Y137622I-1718J-83D01*
G01X280590Y129994D02*
X280000Y126500D01*
G01X279390Y130095D02*
X278828Y126772D01*
G01X280590Y131194D02*
Y129994D01*
G01X279390Y131194D02*
Y130095D01*
G01X281690Y133850D02*
G03X280590Y131194I2656J-2656D01*
G01X280840Y134699D02*
G03X279390Y131194I3507J-3503D01*
G01X283396Y135557D02*
X281690Y133850D01*
G01X282547Y136406D02*
X280840Y134699D01*
G01X284252Y137622D02*
G02X283396Y135557I-2921J1D01*
G01X283051Y137622D02*
G02X282547Y136406I-1720J0D01*
G01X283049Y137704D02*
G02X283051Y137622I-1718J-83D01*
G01X284632Y145631D02*
G02X284252Y137622I-37611J-2229D01*
G01X283434Y145560D02*
G02X283049Y137704I-36412J-2153D01*
G01X284758Y148919D02*
G03X284632Y145631I16669J-2285D01*
G01X283569Y149082D02*
G03X283434Y145560I17858J-2448D01*
G01X283008Y152234D02*
G02X284758Y148919I-1440J-2879D01*
G01X282472Y151160D02*
G02X283569Y149082I-904J-1806D01*
G01X282567Y152454D02*
X283008Y152234D01*
G01X282024Y151383D02*
X282472Y151160D01*
G01X282023Y151383D02*
X282024D01*
G01X282561Y152456D02*
X282562D01*
G01X282024Y151383D02*
X282472Y151160D01*
G01X348590Y214091D02*
G02X346574Y217306I2321J3695D01*
G01D02*
G02X346163Y224725I66709J7416D01*
G01D02*
Y230150D01*
G01D02*
G02X346958Y231808I2122J2D01*
G01D02*
X348062Y232360D01*
G01X346958Y231808D02*
X348062Y232360D01*
G01X346958Y231808D02*
X348062Y232360D01*
G01X346163Y230150D02*
G02X346958Y231808I2122J2D01*
G01X346163Y224725D02*
Y230150D01*
G01X346574Y217306D02*
G02X346163Y224725I66709J7416D01*
G01X348590Y214091D02*
G02X346574Y217306I2321J3695D01*
G01X335233Y206324D02*
X380338Y174741D01*
G01X336095Y207186D02*
X380809Y175877D01*
G01X334617Y207203D02*
X335233Y206324D01*
G01X335753Y207674D02*
X336095Y207186D01*
G01X334169Y209743D02*
X334617Y207203D01*
G01X335366Y209869D02*
X335753Y207674D01*
G01X334093Y211914D02*
X334169Y209743D01*
G01X335293Y211956D02*
X335366Y209869D01*
G01X332840Y214091D02*
G02X334093Y211914I-1430J-2272D01*
G01X333479Y215107D02*
G02X335293Y211956I-2068J-3288D01*
G01X330824Y217306D02*
G03X332840Y214091I4337J480D01*
G01X332017Y217438D02*
G03X333479Y215107I3144J348D01*
G01X330413Y224725D02*
G03X330824Y217306I67120J-3D01*
G01X331613Y224725D02*
G03X332017Y217438I65920J0D01*
G01X330413Y230150D02*
Y224725D01*
G01X331613Y230151D02*
Y224725D01*
G01X331208Y231808D02*
G03X330413Y230150I1327J-1656D01*
G01X331883Y230803D02*
G03X331613Y230151I652J-652D01*
G01X332312Y232360D02*
X331208Y231808D01*
G01X332851Y231287D02*
X331883Y230803D01*
G01X332852Y231287D02*
X332851D01*
G01X332314Y232360D02*
X332312D01*
G01X332851Y231287D02*
X331883Y230803D01*
G01X336095Y207186D02*
X380809Y175877D01*
G01X335233Y206324D02*
X380338Y174741D01*
G01X335753Y207674D02*
X336095Y207186D01*
G01X334617Y207203D02*
X335233Y206324D01*
G01X335366Y209869D02*
X335753Y207674D01*
G01X334169Y209743D02*
X334617Y207203D01*
G01X335293Y211956D02*
X335366Y209869D01*
G01X334093Y211914D02*
X334169Y209743D01*
G01X333479Y215107D02*
G02X335293Y211956I-2068J-3288D01*
G01X332840Y214091D02*
G02X334093Y211914I-1430J-2272D01*
G01X332017Y217438D02*
G03X333479Y215107I3144J348D01*
G01X330824Y217306D02*
G03X332840Y214091I4337J480D01*
G01X331613Y224725D02*
G03X332017Y217438I65920J0D01*
G01X330413Y224725D02*
G03X330824Y217306I67120J-3D01*
G01X331613Y230151D02*
Y224725D01*
G01X330413Y230150D02*
Y224725D01*
G01X331883Y230803D02*
G03X331613Y230151I652J-652D01*
G01X331208Y231808D02*
G03X330413Y230150I1327J-1656D01*
G01X332851Y231287D02*
X331883Y230803D01*
G01X332312Y232360D02*
X331208Y231808D01*
G01X332314Y232360D02*
X332312D01*
G01X332852Y231287D02*
X332851D01*
G01X332312Y232360D02*
X331208Y231808D01*
G01X405434Y-71378D02*
Y-42638D01*
G01X403466Y-73346D02*
X405434Y-71378D01*
G01X398042Y-45340D02*
Y-38879D01*
G01X399242Y-45346D02*
Y-38879D01*
G01X396093Y-50977D02*
X398014Y-47098D01*
G01X399090Y-47630D02*
X399159Y-47491D01*
G01X397293Y-51258D02*
X399090Y-47630D01*
G01X396093Y-56828D02*
Y-50977D01*
G01X397293Y-56975D02*
Y-51258D01*
G01X386644Y-56278D02*
Y-57167D01*
G01X387844Y-56330D02*
Y-57055D01*
G01X387115Y-50771D02*
X386644Y-56278D01*
G01X388300Y-51000D02*
X387844Y-56330D01*
G01X387152Y-50650D02*
X387115Y-50771D01*
G01X388873Y-49124D02*
X388300Y-51000D01*
G01X387682Y-48913D02*
X387152Y-50650D01*
G01X388873Y-49124D02*
X388300Y-51000D01*
G01X387765Y-47361D02*
X387682Y-48913D01*
G01X388964Y-47425D02*
X388873Y-49124D01*
G01X387662Y-45781D02*
X387761Y-47353D01*
G01X388864Y-45771D02*
X388968Y-47417D01*
G01X387836Y-42020D02*
X387662Y-45781D01*
G01X389035Y-42079D02*
X388864Y-45771D01*
G01X387842Y-38879D02*
Y-41945D01*
G01X389042Y-38879D02*
Y-41945D01*
G01X377642Y-41889D02*
Y-38879D01*
G01X378842Y-41975D02*
Y-38879D01*
G01X377316Y-44148D02*
X377642Y-41889D01*
G01X378524Y-44183D02*
X378842Y-41975D01*
G01X377462Y-45856D02*
X377316Y-44148D01*
G01X378658Y-45755D02*
X378524Y-44183D01*
G01X377624Y-47785D02*
X377462Y-45856D01*
G01X378841Y-47934D02*
X378658Y-45755D01*
G01X377427Y-49502D02*
X377629Y-47848D01*
G01X378624Y-49601D02*
X378825Y-47959D01*
G01X377196Y-54814D02*
X377427Y-49502D01*
G01X378396Y-54841D02*
X378624Y-49601D01*
G01X377196Y-57025D02*
Y-54814D01*
G01X378396Y-56778D02*
Y-54841D01*
G01X367471Y-43165D02*
Y-38908D01*
G01X368671Y-43299D02*
Y-38480D01*
G01X367357Y-44810D02*
X367471Y-43165D01*
G01X368557Y-44852D02*
X368669Y-43248D01*
G01X367286Y-47717D02*
X367360Y-47223D01*
G01X368480Y-47847D02*
X368547Y-47400D01*
G01X367747Y-55641D02*
X367274Y-47892D01*
G01X368947Y-55604D02*
X368477Y-47897D01*
G01X367747Y-56874D02*
Y-55641D01*
G01X368947Y-57029D02*
Y-55604D01*
G01X357242Y-43429D02*
Y-38879D01*
G01X358442D02*
Y-43454D01*
G01X357130Y-46201D02*
X357242Y-43429D01*
G01X358442Y-43454D02*
X358329Y-46256D01*
G01X357101Y-46756D02*
X357130Y-46201D01*
G01X358329Y-46257D02*
X358303Y-46757D01*
G01X357297Y-50578D02*
X357101Y-46756D01*
G01X358303Y-46757D02*
X358493Y-50450D01*
G01X358298Y-56330D02*
X357300Y-50600D01*
G01X358493Y-50450D02*
X359498Y-56226D01*
G01X358298Y-57112D02*
Y-56330D01*
G01X359498Y-56226D02*
Y-57136D01*
G01X399242Y-45346D02*
Y-38879D01*
G01X398042Y-45340D02*
Y-38879D01*
G01X399090Y-47630D02*
X399159Y-47491D01*
G01X396093Y-50977D02*
X398014Y-47098D01*
G01X397293Y-51258D02*
X399090Y-47630D01*
G01X396093Y-50977D02*
X398014Y-47098D01*
G01X397293Y-56975D02*
Y-51258D01*
G01X396093Y-56828D02*
Y-50977D01*
G01X387844Y-56330D02*
Y-57055D01*
G01X386644Y-56278D02*
Y-57167D01*
G01X388300Y-51000D02*
X387844Y-56330D01*
G01X387115Y-50771D02*
X386644Y-56278D01*
G01X388873Y-49124D02*
X388300Y-51000D01*
G01X387152Y-50650D02*
X387115Y-50771D01*
G01X387682Y-48913D02*
X387152Y-50650D01*
G01X388964Y-47425D02*
X388873Y-49124D01*
G01X387765Y-47361D02*
X387682Y-48913D01*
G01X388864Y-45771D02*
X388968Y-47417D01*
G01X387662Y-45781D02*
X387761Y-47353D01*
G01X389035Y-42079D02*
X388864Y-45771D01*
G01X387836Y-42020D02*
X387662Y-45781D01*
G01X389042Y-38879D02*
Y-41945D01*
G01X387842Y-38879D02*
Y-41945D01*
G01X378842Y-41975D02*
Y-38879D01*
G01X377642Y-41889D02*
Y-38879D01*
G01X378524Y-44183D02*
X378842Y-41975D01*
G01X377316Y-44148D02*
X377642Y-41889D01*
G01X378658Y-45755D02*
X378524Y-44183D01*
G01X377462Y-45856D02*
X377316Y-44148D01*
G01X378841Y-47934D02*
X378658Y-45755D01*
G01X377624Y-47785D02*
X377462Y-45856D01*
G01X378624Y-49601D02*
X378825Y-47959D01*
G01X377427Y-49502D02*
X377629Y-47848D01*
G01X378396Y-54841D02*
X378624Y-49601D01*
G01X377196Y-54814D02*
X377427Y-49502D01*
G01X378396Y-56778D02*
Y-54841D01*
G01X377196Y-57025D02*
Y-54814D01*
G01X368671Y-43299D02*
Y-38480D01*
G01X367471Y-43165D02*
Y-38908D01*
G01X368557Y-44852D02*
X368669Y-43248D01*
G01X367357Y-44810D02*
X367471Y-43165D01*
G01X368480Y-47847D02*
X368547Y-47400D01*
G01X367286Y-47717D02*
X367360Y-47223D01*
G01X368947Y-55604D02*
X368477Y-47897D01*
G01X367747Y-55641D02*
X367274Y-47892D01*
G01X368947Y-57029D02*
Y-55604D01*
G01X367747Y-56874D02*
Y-55641D01*
G01X359498Y-56226D02*
Y-57136D01*
G01X358298Y-57112D02*
Y-56330D01*
G01X358493Y-50450D02*
X359498Y-56226D01*
G01X358298Y-56330D02*
X357300Y-50600D01*
G01X358303Y-46757D02*
X358493Y-50450D01*
G01X357297Y-50578D02*
X357101Y-46756D01*
G01X358329Y-46257D02*
X358303Y-46757D01*
G01X357101Y-46756D02*
X357130Y-46201D01*
G01X358442Y-43454D02*
X358329Y-46256D01*
G01X357130Y-46201D02*
X357242Y-43429D01*
G01X358442Y-38879D02*
Y-43454D01*
G01X357242Y-43429D02*
Y-38879D01*
G01X350039Y-56286D02*
X350049Y-56330D01*
G01X348388Y-54448D02*
X348849Y-56466D01*
G01X349558Y-54181D02*
X350039Y-56286D01*
G01X348388Y-54448D02*
X348849Y-56466D01*
G01X348077Y-47688D02*
X349558Y-54181D01*
G01X348053Y-47515D02*
X348077Y-47688D01*
G01X348242Y-43457D02*
X348053Y-47515D01*
G01X348242Y-38879D02*
Y-43457D01*
G01X348388Y-54448D02*
X348849Y-56466D01*
G01X350039Y-56286D02*
X350049Y-56330D01*
G01X349558Y-54181D02*
X350039Y-56286D01*
G01X348077Y-47688D02*
X349558Y-54181D01*
G01X348053Y-47515D02*
X348077Y-47688D01*
G01X348242Y-43457D02*
X348053Y-47515D01*
G01X348242Y-38879D02*
Y-43457D01*
G01X406221Y-41850D02*
X439883D01*
G01X406221D02*
G03X405434Y-42638I1J-788D01*
G01X402886Y108332D02*
X353098Y99554D01*
G01X403356Y107196D02*
X353568Y98418D01*
G01X403356Y107196D02*
X353568Y98418D01*
G01X402886Y108332D02*
X353098Y99554D01*
G01X399043Y183240D02*
X459128Y172647D01*
G01X459598Y173783D02*
X399513Y184376D01*
G01X390038Y179612D02*
X457550Y167707D01*
G01X457080Y166571D02*
X389568Y178476D01*
G01X353629Y205106D02*
X390038Y179612D01*
G01X389568Y178476D02*
X352767Y204244D01*
G01X459598Y173783D02*
X399513Y184376D01*
G01X399043Y183240D02*
X459128Y172647D01*
G01X389568Y178476D02*
X352767Y204244D01*
G01X353629Y205106D02*
X390038Y179612D01*
G01X457080Y166571D02*
X389568Y178476D01*
G01X390038Y179612D02*
X457550Y167707D01*
G01X380338Y174741D02*
X455229Y161536D01*
G01X380809Y175877D02*
X455699Y162672D01*
G01X380809Y175877D02*
X455699Y162672D01*
G01X380338Y174741D02*
X455229Y161536D01*
G01X348275Y124587D02*
X347289Y123897D01*
G01X349904Y125728D02*
X348276Y124588D01*
G01X349858Y127755D02*
X349042Y126590D01*
G01X350994Y127285D02*
X349904Y125728D01*
G01X350100Y129128D02*
X349858Y127755D01*
G01X351300Y129023D02*
X350994Y127285D01*
G01X350100Y130723D02*
Y129128D01*
G01X351300Y130722D02*
Y129023D01*
G01X351494Y134089D02*
G03X350100Y130723I3367J-3366D01*
G01X352343Y133240D02*
G03X351300Y130722I2518J-2518D01*
G01X353325Y135920D02*
X351494Y134089D01*
G01X354174Y135071D02*
X352343Y133240D01*
G01X354037Y137640D02*
G02X353325Y135920I-2432J0D01*
G01X355238Y137640D02*
G02X354174Y135071I-3633J0D01*
G01X354038Y139712D02*
Y137639D01*
G01X355238Y139713D02*
Y137640D01*
G01X354781Y141511D02*
G03X354038Y139712I1800J-1796D01*
G01X355631Y140662D02*
G03X355238Y139713I949J-949D01*
G01X356344Y143074D02*
X354781Y141511D01*
G01X357193Y142225D02*
X355631Y140662D01*
G01X358269Y143870D02*
G03X356344Y143074I-2J-2722D01*
G01X358269Y142670D02*
G03X357193Y142225I-1J-1521D01*
G01X361972Y147573D02*
G02X358269Y143870I-3703J0D01*
G01X363172Y147573D02*
G02X358269Y142670I-4903J0D01*
G01X361972Y149395D02*
Y147573D01*
G01X363172Y149396D02*
Y147573D01*
G01X363209Y152157D02*
G03X361972Y149395I2460J-2760D01*
G01X363903Y151161D02*
G03X363172Y149396I1765J-1765D01*
G01X363813Y152458D02*
X363209Y152157D01*
G01X364351Y151385D02*
X363903Y151161D01*
G01X364352Y151385D02*
X364351D01*
G01X363814Y152458D02*
X363813D01*
G01X364351Y151385D02*
X363903Y151161D01*
G01X379558Y152458D02*
X379559D01*
G01X380096Y151385D02*
X379648Y151161D01*
G01X378954Y152157D02*
X379558Y152458D01*
G01X380096Y151385D02*
X379648Y151161D01*
G01X380097Y151385D02*
X380096D01*
G01X377717Y149395D02*
G02X378954Y152157I3697J2D01*
G01X379648Y151161D02*
G03X378917Y149396I1765J-1765D01*
G01X377717Y147573D02*
Y149395D01*
G01X378917Y149396D02*
Y147573D01*
G01X374014Y143870D02*
G03X377717Y147573I0J3703D01*
G01X378917D02*
G02X374014Y142670I-4903J0D01*
G01X372089Y143074D02*
G02X374014Y143870I1923J-1926D01*
G01Y142670D02*
G03X372938Y142225I-1J-1521D01*
G01X370526Y141511D02*
X372089Y143074D01*
G01X372938Y142225D02*
X371376Y140662D01*
G01X369783Y139712D02*
G02X370526Y141511I2543J3D01*
G01X371376Y140662D02*
G03X370983Y139713I949J-949D01*
G01X369783Y137639D02*
Y139712D01*
G01X370983Y139713D02*
Y137640D01*
G01X369070Y135920D02*
G03X369782Y137640I-1720J1720D01*
G01X370983D02*
G02X369919Y135071I-3633J0D01*
G01X367239Y134089D02*
X369070Y135920D01*
G01X369919Y135071D02*
X368088Y133240D01*
G01X365844Y130722D02*
G02X367239Y134089I4762J0D01*
G01X368088Y133240D02*
G03X367045Y130722I2518J-2518D01*
G01X365698Y128443D02*
G03X365844Y130722I-17698J2278D01*
G01X366987Y129238D02*
G02X366848Y127992I-18987J1487D01*
G01X367045Y130722D02*
G02X366987Y129239I-19044J2D01*
G01X364366Y126542D02*
X365698Y128443D01*
G01X366848Y127992D02*
X365228Y125680D01*
G01X361711Y124683D02*
X364366Y126542D01*
G01X365228Y125680D02*
X362400Y123700D01*
G01X358241Y122253D02*
X361711Y124683D01*
G01X362400Y123700D02*
X358711Y121117D01*
G01X395308Y152458D02*
X395309D01*
G01X395846Y151385D02*
X395398Y151161D01*
G01X394704Y152157D02*
X395308Y152458D01*
G01X395846Y151385D02*
X395398Y151161D01*
G01X395847Y151385D02*
X395846D01*
G01X393467Y149395D02*
G02X394704Y152157I3697J2D01*
G01X395398Y151161D02*
G03X394667Y149396I1765J-1765D01*
G01X393467Y147573D02*
Y149395D01*
G01X394667Y149396D02*
Y147573D01*
G01X389764Y143870D02*
G03X393467Y147573I0J3703D01*
G01X394667D02*
G02X389764Y142670I-4903J0D01*
G01X387839Y143074D02*
G02X389764Y143870I1923J-1926D01*
G01Y142670D02*
G03X388688Y142225I-1J-1521D01*
G01X386276Y141511D02*
X387839Y143074D01*
G01X388688Y142225D02*
X387126Y140662D01*
G01X385533Y139712D02*
G02X386276Y141511I2543J3D01*
G01X387126Y140662D02*
G03X386733Y139713I949J-949D01*
G01X385533Y137639D02*
Y139712D01*
G01X386733Y139713D02*
Y137640D01*
G01X384820Y135920D02*
G03X385532Y137640I-1720J1720D01*
G01X386733D02*
G02X385669Y135071I-3633J0D01*
G01X382989Y134089D02*
X384820Y135920D01*
G01X385669Y135071D02*
X383838Y133240D01*
G01X381595Y130723D02*
G02X382989Y134089I4761J0D01*
G01X383838Y133240D02*
G03X382796Y130723I2519J-2517D01*
G01X381075Y127773D02*
X381595Y130723D01*
G01X382795Y130618D02*
X382211Y127303D01*
G01X380517Y126976D02*
X381075Y127773D01*
G01X382211Y127303D02*
X381379Y126114D01*
G01X380515Y126974D02*
X380517Y126976D01*
G01X381364Y126113D02*
X380161Y124910D01*
G01X379386Y125834D02*
X380515Y126962D01*
G01X381364Y126113D02*
X380161Y124910D01*
G01X381378Y126113D02*
X381364D01*
G01X369174Y118682D02*
X379386Y125834D01*
G01X380161Y124910D02*
X369644Y117546D01*
G01X351592Y115582D02*
X369174Y118682D01*
G01X369644Y117546D02*
X351800Y114400D01*
G01X411053Y152458D02*
X411054D01*
G01X411591Y151385D02*
X411143Y151161D01*
G01X410449Y152157D02*
X411053Y152458D01*
G01X411591Y151385D02*
X411143Y151161D01*
G01X411592Y151385D02*
X411591D01*
G01X409212Y149395D02*
G02X410449Y152157I3697J2D01*
G01X411143Y151161D02*
G03X410412Y149396I1765J-1765D01*
G01X409212Y147573D02*
Y149395D01*
G01X410412Y149396D02*
Y147573D01*
G01X405509Y143870D02*
G03X409212Y147573I0J3703D01*
G01X410412D02*
G02X405509Y142670I-4903J0D01*
G01X403584Y143074D02*
G02X405509Y143870I1923J-1926D01*
G01Y142670D02*
G03X404433Y142225I-1J-1521D01*
G01X402021Y141511D02*
X403584Y143074D01*
G01X404433Y142225D02*
X402871Y140662D01*
G01X401278Y139712D02*
G02X402021Y141511I2543J3D01*
G01X402871Y140662D02*
G03X402478Y139713I949J-949D01*
G01X401278Y137639D02*
Y139712D01*
G01X402478Y139713D02*
Y137640D01*
G01X400565Y135920D02*
G03X401277Y137640I-1720J1720D01*
G01X402478D02*
G02X401414Y135071I-3633J0D01*
G01X398734Y134089D02*
X400565Y135920D01*
G01X401414Y135071D02*
X399583Y133240D01*
G01X397340Y130723D02*
G02X398734Y134089I4761J0D01*
G01X399583Y133240D02*
G03X398540Y130722I2518J-2518D01*
G01X397340Y129020D02*
Y130723D01*
G01X398540Y130722D02*
Y128915D01*
G01X397112Y127727D02*
X397340Y129020D01*
G01X398540Y128915D02*
X398248Y127257D01*
G01X394732Y124324D02*
X397112Y127727D01*
G01X398248Y127257D02*
X395595Y123462D01*
G01X382886Y116030D02*
X394732Y124324D01*
G01X395595Y123462D02*
X383356Y114894D01*
G01X378412Y115241D02*
X382886Y116030D01*
G01X383356Y114894D02*
X378882Y114105D01*
G01X349860Y110208D02*
X378412Y115241D01*
G01X377572Y113874D02*
X350330Y109072D01*
G01X378882Y114105D02*
X377572Y113874D01*
G01X398037Y113819D02*
X351630Y105636D01*
G01X398507Y112683D02*
X352100Y104500D01*
G01X406411Y119683D02*
X398037Y113819D01*
G01X407100Y118700D02*
X398507Y112683D01*
G01X409303Y121708D02*
X406411Y119683D01*
G01X410165Y120846D02*
X407100Y118700D01*
G01X412384Y126108D02*
X409303Y121708D01*
G01X413460Y125551D02*
X410165Y120846D01*
G01X412904Y127558D02*
X412384Y126108D01*
G01X414034Y127154D02*
X413460Y125551D01*
G01X413152Y130078D02*
X412900Y127600D01*
G01X414361Y130104D02*
X414064Y127182D01*
G01X414484Y134089D02*
G03X413152Y130078I3334J-3334D01*
G01X415333Y133240D02*
G03X414340Y130250I2485J-2485D01*
G01X416315Y135920D02*
X414484Y134089D01*
G01X417164Y135071D02*
X415333Y133240D01*
G01X417027Y137640D02*
G02X416315Y135920I-2432J0D01*
G01X418228Y137640D02*
G02X417164Y135071I-3633J0D01*
G01X417028Y139712D02*
Y137639D01*
G01X418228Y139713D02*
Y137640D01*
G01X417771Y141511D02*
G03X417028Y139712I1800J-1796D01*
G01X418621Y140662D02*
G03X418228Y139713I949J-949D01*
G01X419334Y143074D02*
X417771Y141511D01*
G01X420183Y142225D02*
X418621Y140662D01*
G01X421259Y143870D02*
G03X419334Y143074I-2J-2722D01*
G01X421259Y142670D02*
G03X420183Y142225I-1J-1521D01*
G01X424962Y147573D02*
G02X421259Y143870I-3703J0D01*
G01X426162Y147573D02*
G02X421259Y142670I-4903J0D01*
G01X424962Y149395D02*
Y147573D01*
G01X426162Y149396D02*
Y147573D01*
G01X426199Y152157D02*
G03X424962Y149395I2460J-2760D01*
G01X426893Y151161D02*
G03X426162Y149396I1765J-1765D01*
G01X426803Y152458D02*
X426199Y152157D01*
G01X427341Y151385D02*
X426893Y151161D01*
G01X426804Y152458D02*
X426803D01*
G01X427341Y151385D02*
X426893Y151161D01*
G01X419811Y120183D02*
X402886Y108332D01*
G01X420500Y119200D02*
X403356Y107196D01*
G01X426309Y124734D02*
X419811Y120183D01*
G01X427084Y123810D02*
X420500Y119200D01*
G01X427665Y126089D02*
X426309Y124734D01*
G01X428514Y125240D02*
X427084Y123810D01*
G01X428514Y125240D02*
X427084Y123810D01*
G01X348275Y124587D02*
X347289Y123897D01*
G01X349904Y125728D02*
X348276Y124588D01*
G01X350994Y127285D02*
X349904Y125728D01*
G01X349858Y127755D02*
X349042Y126590D01*
G01X351300Y129023D02*
X350994Y127285D01*
G01X350100Y129128D02*
X349858Y127755D01*
G01X351300Y130722D02*
Y129023D01*
G01X350100Y130723D02*
Y129128D01*
G01X352343Y133240D02*
G03X351300Y130722I2518J-2518D01*
G01X351494Y134089D02*
G03X350100Y130723I3367J-3366D01*
G01X354174Y135071D02*
X352343Y133240D01*
G01X353325Y135920D02*
X351494Y134089D01*
G01X355238Y137640D02*
G02X354174Y135071I-3633J0D01*
G01X354037Y137640D02*
G02X353325Y135920I-2432J0D01*
G01X355238Y139713D02*
Y137640D01*
G01X354038Y139712D02*
Y137639D01*
G01X355631Y140662D02*
G03X355238Y139713I949J-949D01*
G01X354781Y141511D02*
G03X354038Y139712I1800J-1796D01*
G01X357193Y142225D02*
X355631Y140662D01*
G01X356344Y143074D02*
X354781Y141511D01*
G01X358269Y142670D02*
G03X357193Y142225I-1J-1521D01*
G01X358269Y143870D02*
G03X356344Y143074I-2J-2722D01*
G01X363172Y147573D02*
G02X358269Y142670I-4903J0D01*
G01X361972Y147573D02*
G02X358269Y143870I-3703J0D01*
G01X363172Y149396D02*
Y147573D01*
G01X361972Y149395D02*
Y147573D01*
G01X363903Y151161D02*
G03X363172Y149396I1765J-1765D01*
G01X363209Y152157D02*
G03X361972Y149395I2460J-2760D01*
G01X364351Y151385D02*
X363903Y151161D01*
G01X363813Y152458D02*
X363209Y152157D01*
G01X363814Y152458D02*
X363813D01*
G01X364352Y151385D02*
X364351D01*
G01X363813Y152458D02*
X363209Y152157D01*
G01X362400Y123700D02*
X358711Y121117D01*
G01X358241Y122253D02*
X361711Y124683D01*
G01X365228Y125680D02*
X362400Y123700D01*
G01X361711Y124683D02*
X364366Y126542D01*
G01X366848Y127992D02*
X365228Y125680D01*
G01X364366Y126542D02*
X365698Y128443D01*
G01X366987Y129238D02*
G02X366848Y127992I-18987J1487D01*
G01X365698Y128443D02*
G03X365844Y130722I-17698J2278D01*
G01X367045D02*
G02X366987Y129239I-19044J2D01*
G01X365698Y128443D02*
G03X365844Y130722I-17698J2278D01*
G01X368088Y133240D02*
G03X367045Y130722I2518J-2518D01*
G01X365844D02*
G02X367239Y134089I4762J0D01*
G01X369919Y135071D02*
X368088Y133240D01*
G01X367239Y134089D02*
X369070Y135920D01*
G01X370983Y137640D02*
G02X369919Y135071I-3633J0D01*
G01X369070Y135920D02*
G03X369782Y137640I-1720J1720D01*
G01X370983Y139713D02*
Y137640D01*
G01X369783Y137639D02*
Y139712D01*
G01X371376Y140662D02*
G03X370983Y139713I949J-949D01*
G01X369783Y139712D02*
G02X370526Y141511I2543J3D01*
G01X372938Y142225D02*
X371376Y140662D01*
G01X370526Y141511D02*
X372089Y143074D01*
G01X374014Y142670D02*
G03X372938Y142225I-1J-1521D01*
G01X372089Y143074D02*
G02X374014Y143870I1923J-1926D01*
G01X378917Y147573D02*
G02X374014Y142670I-4903J0D01*
G01Y143870D02*
G03X377717Y147573I0J3703D01*
G01X378917Y149396D02*
Y147573D01*
G01X377717D02*
Y149395D01*
G01X379648Y151161D02*
G03X378917Y149396I1765J-1765D01*
G01X377717Y149395D02*
G02X378954Y152157I3697J2D01*
G01X380096Y151385D02*
X379648Y151161D01*
G01X379558Y152458D02*
X379559D01*
G01X378954Y152157D02*
X379558Y152458D01*
G01X380097Y151385D02*
X380096D01*
G01X378954Y152157D02*
X379558Y152458D01*
G01X369644Y117546D02*
X351800Y114400D01*
G01X351592Y115582D02*
X369174Y118682D01*
G01X380161Y124910D02*
X369644Y117546D01*
G01X369174Y118682D02*
X379386Y125834D01*
G01X381364Y126113D02*
X380161Y124910D01*
G01X380515Y126974D02*
X380517Y126976D01*
G01X379386Y125834D02*
X380515Y126962D01*
G01X381378Y126113D02*
X381364D01*
G01X379386Y125834D02*
X380515Y126962D01*
G01X382211Y127303D02*
X381379Y126114D01*
G01X380517Y126976D02*
X381075Y127773D01*
G01X382795Y130618D02*
X382211Y127303D01*
G01X381075Y127773D02*
X381595Y130723D01*
G01X383838Y133240D02*
G03X382796Y130723I2519J-2517D01*
G01X381595D02*
G02X382989Y134089I4761J0D01*
G01X385669Y135071D02*
X383838Y133240D01*
G01X382989Y134089D02*
X384820Y135920D01*
G01X386733Y137640D02*
G02X385669Y135071I-3633J0D01*
G01X384820Y135920D02*
G03X385532Y137640I-1720J1720D01*
G01X386733Y139713D02*
Y137640D01*
G01X385533Y137639D02*
Y139712D01*
G01X387126Y140662D02*
G03X386733Y139713I949J-949D01*
G01X385533Y139712D02*
G02X386276Y141511I2543J3D01*
G01X388688Y142225D02*
X387126Y140662D01*
G01X386276Y141511D02*
X387839Y143074D01*
G01X389764Y142670D02*
G03X388688Y142225I-1J-1521D01*
G01X387839Y143074D02*
G02X389764Y143870I1923J-1926D01*
G01X394667Y147573D02*
G02X389764Y142670I-4903J0D01*
G01Y143870D02*
G03X393467Y147573I0J3703D01*
G01X394667Y149396D02*
Y147573D01*
G01X393467D02*
Y149395D01*
G01X395398Y151161D02*
G03X394667Y149396I1765J-1765D01*
G01X393467Y149395D02*
G02X394704Y152157I3697J2D01*
G01X395846Y151385D02*
X395398Y151161D01*
G01X395308Y152458D02*
X395309D01*
G01X394704Y152157D02*
X395308Y152458D01*
G01X395847Y151385D02*
X395846D01*
G01X394704Y152157D02*
X395308Y152458D01*
G01X377572Y113874D02*
X350330Y109072D01*
G01X349860Y110208D02*
X378412Y115241D01*
G01X378882Y114105D02*
X377572Y113874D01*
G01X349860Y110208D02*
X378412Y115241D01*
G01X383356Y114894D02*
X378882Y114105D01*
G01X378412Y115241D02*
X382886Y116030D01*
G01X395595Y123462D02*
X383356Y114894D01*
G01X382886Y116030D02*
X394732Y124324D01*
G01X398248Y127257D02*
X395595Y123462D01*
G01X394732Y124324D02*
X397112Y127727D01*
G01X398540Y128915D02*
X398248Y127257D01*
G01X397112Y127727D02*
X397340Y129020D01*
G01X398540Y130722D02*
Y128915D01*
G01X397340Y129020D02*
Y130723D01*
G01X399583Y133240D02*
G03X398540Y130722I2518J-2518D01*
G01X397340Y130723D02*
G02X398734Y134089I4761J0D01*
G01X401414Y135071D02*
X399583Y133240D01*
G01X398734Y134089D02*
X400565Y135920D01*
G01X402478Y137640D02*
G02X401414Y135071I-3633J0D01*
G01X400565Y135920D02*
G03X401277Y137640I-1720J1720D01*
G01X402478Y139713D02*
Y137640D01*
G01X401278Y137639D02*
Y139712D01*
G01X402871Y140662D02*
G03X402478Y139713I949J-949D01*
G01X401278Y139712D02*
G02X402021Y141511I2543J3D01*
G01X404433Y142225D02*
X402871Y140662D01*
G01X402021Y141511D02*
X403584Y143074D01*
G01X405509Y142670D02*
G03X404433Y142225I-1J-1521D01*
G01X403584Y143074D02*
G02X405509Y143870I1923J-1926D01*
G01X410412Y147573D02*
G02X405509Y142670I-4903J0D01*
G01Y143870D02*
G03X409212Y147573I0J3703D01*
G01X410412Y149396D02*
Y147573D01*
G01X409212D02*
Y149395D01*
G01X411143Y151161D02*
G03X410412Y149396I1765J-1765D01*
G01X409212Y149395D02*
G02X410449Y152157I3697J2D01*
G01X411591Y151385D02*
X411143Y151161D01*
G01X411053Y152458D02*
X411054D01*
G01X410449Y152157D02*
X411053Y152458D01*
G01X411592Y151385D02*
X411591D01*
G01X410449Y152157D02*
X411053Y152458D01*
G01X398507Y112683D02*
X352100Y104500D01*
G01X398037Y113819D02*
X351630Y105636D01*
G01X407100Y118700D02*
X398507Y112683D01*
G01X406411Y119683D02*
X398037Y113819D01*
G01X410165Y120846D02*
X407100Y118700D01*
G01X409303Y121708D02*
X406411Y119683D01*
G01X413460Y125551D02*
X410165Y120846D01*
G01X412384Y126108D02*
X409303Y121708D01*
G01X414034Y127154D02*
X413460Y125551D01*
G01X412904Y127558D02*
X412384Y126108D01*
G01X414361Y130104D02*
X414064Y127182D01*
G01X413152Y130078D02*
X412900Y127600D01*
G01X415333Y133240D02*
G03X414340Y130250I2485J-2485D01*
G01X414484Y134089D02*
G03X413152Y130078I3334J-3334D01*
G01X417164Y135071D02*
X415333Y133240D01*
G01X416315Y135920D02*
X414484Y134089D01*
G01X418228Y137640D02*
G02X417164Y135071I-3633J0D01*
G01X417027Y137640D02*
G02X416315Y135920I-2432J0D01*
G01X418228Y139713D02*
Y137640D01*
G01X417028Y139712D02*
Y137639D01*
G01X418621Y140662D02*
G03X418228Y139713I949J-949D01*
G01X417771Y141511D02*
G03X417028Y139712I1800J-1796D01*
G01X420183Y142225D02*
X418621Y140662D01*
G01X419334Y143074D02*
X417771Y141511D01*
G01X421259Y142670D02*
G03X420183Y142225I-1J-1521D01*
G01X421259Y143870D02*
G03X419334Y143074I-2J-2722D01*
G01X426162Y147573D02*
G02X421259Y142670I-4903J0D01*
G01X424962Y147573D02*
G02X421259Y143870I-3703J0D01*
G01X426162Y149396D02*
Y147573D01*
G01X424962Y149395D02*
Y147573D01*
G01X426893Y151161D02*
G03X426162Y149396I1765J-1765D01*
G01X426199Y152157D02*
G03X424962Y149395I2460J-2760D01*
G01X427341Y151385D02*
X426893Y151161D01*
G01X426803Y152458D02*
X426199Y152157D01*
G01X426804Y152458D02*
X426803D01*
G01D02*
X426199Y152157D01*
G01X420500Y119200D02*
X403356Y107196D01*
G01X419811Y120183D02*
X402886Y108332D01*
G01X427084Y123810D02*
X420500Y119200D01*
G01X426309Y124734D02*
X419811Y120183D01*
G01X428514Y125240D02*
X427084Y123810D01*
G01X427665Y126089D02*
X426309Y124734D01*
G01X427665Y126089D02*
X426309Y124734D01*
G01X347422Y149396D02*
Y147573D01*
G01X348153Y151161D02*
G03X347422Y149396I1765J-1765D01*
G01X348063Y152458D02*
X347459Y152157D01*
G01X348601Y151385D02*
X348153Y151161D01*
G01X348602Y151385D02*
X348601D01*
G01X348064Y152458D02*
X348063D01*
G01X348601Y151385D02*
X348153Y151161D01*
G01X347422Y149396D02*
Y147573D01*
G01X348153Y151161D02*
G03X347422Y149396I1765J-1765D01*
G01X348601Y151385D02*
X348153Y151161D01*
G01X348063Y152458D02*
X347459Y152157D01*
G01X348064Y152458D02*
X348063D01*
G01X348602Y151385D02*
X348601D01*
G01X348063Y152458D02*
X347459Y152157D01*
G01X426802Y232360D02*
X426804D01*
G01X426373Y230803D02*
X427341Y231287D01*
G01X425698Y231808D02*
X426802Y232360D01*
G01X426373Y230803D02*
X427341Y231287D01*
G01X424903Y230150D02*
G02X425698Y231808I2122J2D01*
G01X426103Y230151D02*
G02X426373Y230803I922J0D01*
G01X424903Y224725D02*
Y230150D01*
G01X426103Y224725D02*
Y230151D01*
G01X425314Y217306D02*
G02X424903Y224725I66709J7416D01*
G01X426507Y217438D02*
G02X426103Y224725I65516J7287D01*
G01X427330Y214091D02*
G02X425314Y217306I2321J3695D01*
G01X427969Y215107D02*
G02X426507Y217438I1682J2679D01*
G01X411052Y232360D02*
X411054D01*
G01X411591Y231287D02*
X410623Y230803D01*
G01X409948Y231808D02*
X411052Y232360D01*
G01X411591Y231287D02*
X410623Y230803D01*
G01X411592Y231287D02*
X411591D01*
G01X409153Y230150D02*
G02X409948Y231808I2122J2D01*
G01X410623Y230803D02*
G03X410353Y230151I652J-652D01*
G01X409153Y224725D02*
Y230150D01*
G01X410353Y230151D02*
Y224725D01*
G01X409564Y217306D02*
G02X409153Y224725I66709J7416D01*
G01X410353D02*
G03X410757Y217438I65920J0D01*
G01X411580Y214091D02*
G02X409564Y217306I2321J3695D01*
G01X410757Y217438D02*
G03X412219Y215107I3144J348D01*
G01X412833Y211914D02*
G03X411580Y214091I-2683J-95D01*
G01X412219Y215107D02*
G02X414033Y211956I-2068J-3288D01*
G01X412909Y209743D02*
X412833Y211914D01*
G01X414033Y211956D02*
X414106Y209869D01*
G01X413336Y207324D02*
X412909Y209743D01*
G01X414106Y209869D02*
X414472Y207795D01*
G01X414209Y206078D02*
X413336Y207324D01*
G01X414472Y207795D02*
X415071Y206940D01*
G01X430991Y194327D02*
X414209Y206078D01*
G01X415071Y206940D02*
X431461Y195463D01*
G01X422950Y190574D02*
X464766Y183201D01*
G01X422817Y191816D02*
X465236Y184337D01*
G01X420401Y191023D02*
X422950Y190574D01*
G01X420871Y192159D02*
X422817Y191816D01*
G01X398613Y206280D02*
X420401Y191023D01*
G01X399475Y207142D02*
X420871Y192159D01*
G01X397492Y207882D02*
X398613Y206280D01*
G01X398628Y208352D02*
X399475Y207142D01*
G01X397164Y209743D02*
X397492Y207882D01*
G01X398361Y209869D02*
X398628Y208352D01*
G01X397088Y211914D02*
X397164Y209743D01*
G01X398288Y211956D02*
X398361Y209869D01*
G01X395835Y214091D02*
G02X397088Y211914I-1430J-2272D01*
G01X396474Y215107D02*
G02X398288Y211956I-2068J-3288D01*
G01X393819Y217306D02*
G03X395835Y214091I4337J480D01*
G01X395012Y217438D02*
G03X396474Y215107I3144J348D01*
G01X393408Y224725D02*
G03X393819Y217306I67120J-3D01*
G01X394608Y224725D02*
G03X395012Y217438I65920J0D01*
G01X393408Y230150D02*
Y224725D01*
G01X394608Y230151D02*
Y224725D01*
G01X394203Y231808D02*
G03X393408Y230150I1327J-1656D01*
G01X394878Y230803D02*
G03X394608Y230151I652J-652D01*
G01X395307Y232360D02*
X394203Y231808D01*
G01X395846Y231287D02*
X394878Y230803D01*
G01X395847Y231287D02*
X395846D01*
G01X395309Y232360D02*
X395307D01*
G01X395846Y231287D02*
X394878Y230803D01*
G01X408648Y188056D02*
X461825Y178679D01*
G01X409119Y189192D02*
X462295Y179815D01*
G01X382573Y206313D02*
X408648Y188056D01*
G01X383435Y207175D02*
X409119Y189192D01*
G01X381832Y207372D02*
X382573Y206313D01*
G01X382968Y207842D02*
X383435Y207175D01*
G01X381414Y209743D02*
X381832Y207372D01*
G01X382611Y209869D02*
X382968Y207842D01*
G01X381338Y211914D02*
X381414Y209743D01*
G01X382538Y211956D02*
X382611Y209869D01*
G01X380085Y214091D02*
G02X381338Y211914I-1430J-2272D01*
G01X380724Y215107D02*
G02X382538Y211956I-2068J-3288D01*
G01X378069Y217306D02*
G03X380085Y214091I4337J480D01*
G01X379262Y217438D02*
G03X380724Y215107I3144J348D01*
G01X377658Y224725D02*
G03X378069Y217306I67120J-3D01*
G01X378858Y224725D02*
G03X379262Y217438I65920J0D01*
G01X377658Y230150D02*
Y224725D01*
G01X378858Y230151D02*
Y224725D01*
G01X378453Y231808D02*
G03X377658Y230150I1327J-1656D01*
G01X379128Y230803D02*
G03X378858Y230151I652J-652D01*
G01X379557Y232360D02*
X378453Y231808D01*
G01X380096Y231287D02*
X379128Y230803D01*
G01X380097Y231287D02*
X380096D01*
G01X379559Y232360D02*
X379557D01*
G01X380096Y231287D02*
X379128Y230803D01*
G01X425698Y231808D02*
X426802Y232360D01*
G01X426373Y230803D02*
X427341Y231287D01*
G01X426802Y232360D02*
X426804D01*
G01X425698Y231808D02*
X426802Y232360D01*
G01X426103Y230151D02*
G02X426373Y230803I922J0D01*
G01X424903Y230150D02*
G02X425698Y231808I2122J2D01*
G01X426103Y224725D02*
Y230151D01*
G01X424903Y224725D02*
Y230150D01*
G01X426507Y217438D02*
G02X426103Y224725I65516J7287D01*
G01X425314Y217306D02*
G02X424903Y224725I66709J7416D01*
G01X427969Y215107D02*
G02X426507Y217438I1682J2679D01*
G01X427330Y214091D02*
G02X425314Y217306I2321J3695D01*
G01X415071Y206940D02*
X431461Y195463D01*
G01X430991Y194327D02*
X414209Y206078D01*
G01X414472Y207795D02*
X415071Y206940D01*
G01X414209Y206078D02*
X413336Y207324D01*
G01X414106Y209869D02*
X414472Y207795D01*
G01X413336Y207324D02*
X412909Y209743D01*
G01X414033Y211956D02*
X414106Y209869D01*
G01X412909Y209743D02*
X412833Y211914D01*
G01X412219Y215107D02*
G02X414033Y211956I-2068J-3288D01*
G01X412833Y211914D02*
G03X411580Y214091I-2683J-95D01*
G01X410757Y217438D02*
G03X412219Y215107I3144J348D01*
G01X411580Y214091D02*
G02X409564Y217306I2321J3695D01*
G01X410353Y224725D02*
G03X410757Y217438I65920J0D01*
G01X409564Y217306D02*
G02X409153Y224725I66709J7416D01*
G01X410353Y230151D02*
Y224725D01*
G01X409153D02*
Y230150D01*
G01X410623Y230803D02*
G03X410353Y230151I652J-652D01*
G01X409153Y230150D02*
G02X409948Y231808I2122J2D01*
G01X411591Y231287D02*
X410623Y230803D01*
G01X411052Y232360D02*
X411054D01*
G01X409948Y231808D02*
X411052Y232360D01*
G01X411592Y231287D02*
X411591D01*
G01X409948Y231808D02*
X411052Y232360D01*
G01X422817Y191816D02*
X465236Y184337D01*
G01X422950Y190574D02*
X464766Y183201D01*
G01X420871Y192159D02*
X422817Y191816D01*
G01X420401Y191023D02*
X422950Y190574D01*
G01X399475Y207142D02*
X420871Y192159D01*
G01X398613Y206280D02*
X420401Y191023D01*
G01X398628Y208352D02*
X399475Y207142D01*
G01X397492Y207882D02*
X398613Y206280D01*
G01X398361Y209869D02*
X398628Y208352D01*
G01X397164Y209743D02*
X397492Y207882D01*
G01X398288Y211956D02*
X398361Y209869D01*
G01X397088Y211914D02*
X397164Y209743D01*
G01X396474Y215107D02*
G02X398288Y211956I-2068J-3288D01*
G01X395835Y214091D02*
G02X397088Y211914I-1430J-2272D01*
G01X395012Y217438D02*
G03X396474Y215107I3144J348D01*
G01X393819Y217306D02*
G03X395835Y214091I4337J480D01*
G01X394608Y224725D02*
G03X395012Y217438I65920J0D01*
G01X393408Y224725D02*
G03X393819Y217306I67120J-3D01*
G01X394608Y230151D02*
Y224725D01*
G01X393408Y230150D02*
Y224725D01*
G01X394878Y230803D02*
G03X394608Y230151I652J-652D01*
G01X394203Y231808D02*
G03X393408Y230150I1327J-1656D01*
G01X395846Y231287D02*
X394878Y230803D01*
G01X395307Y232360D02*
X394203Y231808D01*
G01X395309Y232360D02*
X395307D01*
G01X395847Y231287D02*
X395846D01*
G01X395307Y232360D02*
X394203Y231808D01*
G01X409119Y189192D02*
X462295Y179815D01*
G01X408648Y188056D02*
X461825Y178679D01*
G01X383435Y207175D02*
X409119Y189192D01*
G01X382573Y206313D02*
X408648Y188056D01*
G01X382968Y207842D02*
X383435Y207175D01*
G01X381832Y207372D02*
X382573Y206313D01*
G01X382611Y209869D02*
X382968Y207842D01*
G01X381414Y209743D02*
X381832Y207372D01*
G01X382538Y211956D02*
X382611Y209869D01*
G01X381338Y211914D02*
X381414Y209743D01*
G01X380724Y215107D02*
G02X382538Y211956I-2068J-3288D01*
G01X380085Y214091D02*
G02X381338Y211914I-1430J-2272D01*
G01X379262Y217438D02*
G03X380724Y215107I3144J348D01*
G01X378069Y217306D02*
G03X380085Y214091I4337J480D01*
G01X378858Y224725D02*
G03X379262Y217438I65920J0D01*
G01X377658Y224725D02*
G03X378069Y217306I67120J-3D01*
G01X378858Y230151D02*
Y224725D01*
G01X377658Y230150D02*
Y224725D01*
G01X379128Y230803D02*
G03X378858Y230151I652J-652D01*
G01X378453Y231808D02*
G03X377658Y230150I1327J-1656D01*
G01X380096Y231287D02*
X379128Y230803D01*
G01X379557Y232360D02*
X378453Y231808D01*
G01X379559Y232360D02*
X379557D01*
G01X380097Y231287D02*
X380096D01*
G01X379557Y232360D02*
X378453Y231808D01*
G01X367447Y205364D02*
X399043Y183240D01*
G01X399513Y184376D02*
X368309Y206226D01*
G01X366103Y207284D02*
X367447Y205364D01*
G01X368309Y206226D02*
X367239Y207754D01*
G01X365669Y209743D02*
X366103Y207284D01*
G01X367239Y207754D02*
X366866Y209869D01*
G01X365593Y211914D02*
X365669Y209743D01*
G01X366866Y209869D02*
X366793Y211956D01*
G01X364340Y214091D02*
G02X365593Y211914I-1430J-2272D01*
G01X366793Y211956D02*
G03X364979Y215107I-3882J-137D01*
G01X362324Y217306D02*
G03X364340Y214091I4337J480D01*
G01X364979Y215107D02*
G02X363517Y217438I1682J2679D01*
G01X361913Y224725D02*
G03X362324Y217306I67120J-3D01*
G01X363517Y217438D02*
G02X363113Y224725I65516J7287D01*
G01X361913Y230150D02*
Y224725D01*
G01X363113D02*
Y230151D01*
G01X362708Y231808D02*
G03X361913Y230150I1327J-1656D01*
G01X363113Y230151D02*
G02X363383Y230803I922J0D01*
G01X363812Y232360D02*
X362708Y231808D01*
G01X364351Y231287D02*
X364352D01*
G01X363383Y230803D02*
X364351Y231287D01*
G01X363814Y232360D02*
X363812D01*
G01X363383Y230803D02*
X364351Y231287D01*
G01X351393Y208299D02*
X353629Y205106D01*
G01X352767Y204244D02*
X350257Y207829D01*
G01X351116Y209869D02*
X351393Y208299D01*
G01X350257Y207829D02*
X349919Y209743D01*
G01X351043Y211956D02*
X351116Y209869D01*
G01X349919Y209743D02*
X349843Y211914D01*
G01X349229Y215107D02*
G02X351043Y211956I-2068J-3288D01*
G01X349843Y211914D02*
G03X348590Y214091I-2683J-95D01*
G01X347767Y217438D02*
G03X349229Y215107I3144J348D01*
G01X347363Y224725D02*
G03X347767Y217438I65920J0D01*
G01X347363Y230151D02*
Y224725D01*
G01X347633Y230803D02*
G03X347363Y230151I652J-652D01*
G01X348601Y231287D02*
X347633Y230803D01*
G01X348062Y232360D02*
X348064D01*
G01X348602Y231287D02*
X348601D01*
G01X364351D02*
X364352D01*
G01X363812Y232360D02*
X362708Y231808D01*
G01X363383Y230803D02*
X364351Y231287D01*
G01X363812Y232360D02*
X362708Y231808D01*
G01X363814Y232360D02*
X363812D01*
G01X363113Y230151D02*
G02X363383Y230803I922J0D01*
G01X362708Y231808D02*
G03X361913Y230150I1327J-1656D01*
G01X363113Y224725D02*
Y230151D01*
G01X361913Y230150D02*
Y224725D01*
G01X363517Y217438D02*
G02X363113Y224725I65516J7287D01*
G01X361913D02*
G03X362324Y217306I67120J-3D01*
G01X364979Y215107D02*
G02X363517Y217438I1682J2679D01*
G01X362324Y217306D02*
G03X364340Y214091I4337J480D01*
G01X366793Y211956D02*
G03X364979Y215107I-3882J-137D01*
G01X364340Y214091D02*
G02X365593Y211914I-1430J-2272D01*
G01X366866Y209869D02*
X366793Y211956D01*
G01X365593Y211914D02*
X365669Y209743D01*
G01X367239Y207754D02*
X366866Y209869D01*
G01X365669Y209743D02*
X366103Y207284D01*
G01X368309Y206226D02*
X367239Y207754D01*
G01X366103Y207284D02*
X367447Y205364D01*
G01X399513Y184376D02*
X368309Y206226D01*
G01X367447Y205364D02*
X399043Y183240D01*
G01X348062Y232360D02*
X348064D01*
G01X348601Y231287D02*
X347633Y230803D01*
G01X348601Y231287D02*
X347633Y230803D01*
G01X348602Y231287D02*
X348601D01*
G01X347633Y230803D02*
G03X347363Y230151I652J-652D01*
G01D02*
Y224725D01*
G01D02*
G03X347767Y217438I65920J0D01*
G01D02*
G03X349229Y215107I3144J348D01*
G01X349843Y211914D02*
G03X348590Y214091I-2683J-95D01*
G01X349229Y215107D02*
G02X351043Y211956I-2068J-3288D01*
G01X349919Y209743D02*
X349843Y211914D01*
G01X351043Y211956D02*
X351116Y209869D01*
G01X350257Y207829D02*
X349919Y209743D01*
G01X351116Y209869D02*
X351393Y208299D01*
G01X352767Y204244D02*
X350257Y207829D01*
G01X351393Y208299D02*
X353629Y205106D01*
G01X428505Y563228D02*
X426536Y565196D01*
G01X442639Y-73346D02*
X538111D01*
G01X440670Y-71378D02*
X442639Y-73346D01*
G01X440670Y-42638D02*
Y-71378D01*
G01X506621Y-45123D02*
X509597Y62113D01*
G01X508565Y-56144D02*
X506621Y-45123D01*
G01X499199Y-53177D02*
X504449Y60988D01*
G01X500528Y-50407D02*
X500400Y-53200D01*
G01X500730Y-46032D02*
X500661Y-47530D01*
G01X505650Y60962D02*
X500862Y-43155D01*
G01X499223Y-56342D02*
X499200Y-53208D01*
G01X500400Y-53200D02*
X500423Y-56334D01*
G01X499223Y-57630D02*
G02Y-57534I2864J48D01*
G01X500423D02*
G03X500910Y-58710I1663J0D01*
G01X489559Y-51877D02*
X489774Y-57629D01*
G01X490761Y-51905D02*
X490974Y-57585D01*
G01X499389Y62327D02*
X489559Y-51876D01*
G01X491092Y-48060D02*
X490761Y-51905D01*
G01X491468Y-43696D02*
X491339Y-45191D01*
G01X500590Y62277D02*
X491715Y-40827D01*
G01X480325Y-49089D02*
Y-57653D01*
G01X481525Y-49194D02*
Y-57736D01*
G01X480818Y-46292D02*
X480325Y-49089D01*
G01X482000Y-46500D02*
X481525Y-49194D01*
G01X482005Y-46471D02*
X482000Y-46500D01*
G01X494592Y63986D02*
X480818Y-46292D01*
G01X482211Y-44824D02*
X482005Y-46471D01*
G01X482754Y-40477D02*
X482568Y-41966D01*
G01X495806Y64017D02*
X483111Y-37620D01*
G01X506621Y-45123D02*
X509597Y62113D01*
G01X508565Y-56144D02*
X506621Y-45123D01*
G01X508565Y-56144D02*
X506621Y-45123D01*
G01X508565Y-56144D02*
X506621Y-45123D01*
G01X500423Y-57534D02*
G03X500910Y-58710I1663J0D01*
G01X499223Y-57630D02*
G02Y-57534I2864J48D01*
G01X500400Y-53200D02*
X500423Y-56334D01*
G01X499223Y-56342D02*
X499200Y-53208D01*
G01X500528Y-50407D02*
X500400Y-53200D01*
G01X499199Y-53177D02*
X504449Y60988D01*
G01X500730Y-46032D02*
X500661Y-47530D01*
G01X499199Y-53177D02*
X504449Y60988D01*
G01X505650Y60962D02*
X500862Y-43155D01*
G01X499199Y-53177D02*
X504449Y60988D01*
G01X490761Y-51905D02*
X490974Y-57585D01*
G01X489559Y-51877D02*
X489774Y-57629D01*
G01X491092Y-48060D02*
X490761Y-51905D01*
G01X499389Y62327D02*
X489559Y-51876D01*
G01X491468Y-43696D02*
X491339Y-45191D01*
G01X499389Y62327D02*
X489559Y-51876D01*
G01X500590Y62277D02*
X491715Y-40827D01*
G01X499389Y62327D02*
X489559Y-51876D01*
G01X481525Y-49194D02*
Y-57736D01*
G01X480325Y-49089D02*
Y-57653D01*
G01X482000Y-46500D02*
X481525Y-49194D01*
G01X480818Y-46292D02*
X480325Y-49089D01*
G01X482005Y-46471D02*
X482000Y-46500D01*
G01X480818Y-46292D02*
X480325Y-49089D01*
G01X482211Y-44824D02*
X482005Y-46471D01*
G01X494592Y63986D02*
X480818Y-46292D01*
G01X482754Y-40477D02*
X482568Y-41966D01*
G01X494592Y63986D02*
X480818Y-46292D01*
G01X495806Y64017D02*
X483111Y-37620D01*
G01X494592Y63986D02*
X480818Y-46292D01*
G01X470877Y-49567D02*
Y-57677D01*
G01X472077Y-57688D02*
Y-49672D01*
G01X489585Y64253D02*
X470877Y-49567D01*
G01X474224Y-36611D02*
X490785Y64154D01*
G01X473756Y-39453D02*
X474224Y-36611D01*
G01X473513Y-40933D02*
X473756Y-39453D01*
G01X472803Y-45255D02*
X473046Y-43775D01*
G01X472077Y-49672D02*
X472336Y-48097D01*
G01X462628Y-49810D02*
Y-57639D01*
G01X461428Y-57801D02*
Y-49705D01*
G01X463000Y-47700D02*
X462628Y-49810D01*
G01X461428Y-49705D02*
X461818Y-47492D01*
G01X463297Y-46230D02*
X463000Y-47700D01*
G01X461820Y-47477D02*
X484315Y63990D01*
G01X464163Y-41936D02*
X463866Y-43407D01*
G01X461820Y-47477D02*
X484315Y63990D01*
G01X485508Y63832D02*
X464733Y-39113D01*
G01X461820Y-47477D02*
X484315Y63990D01*
G01X474224Y-36611D02*
X490785Y64154D01*
G01X489585Y64253D02*
X470877Y-49567D01*
G01X473756Y-39453D02*
X474224Y-36611D01*
G01X489585Y64253D02*
X470877Y-49567D01*
G01X473513Y-40933D02*
X473756Y-39453D01*
G01X489585Y64253D02*
X470877Y-49567D01*
G01X472803Y-45255D02*
X473046Y-43775D01*
G01X489585Y64253D02*
X470877Y-49567D01*
G01X472077Y-49672D02*
X472336Y-48097D01*
G01X489585Y64253D02*
X470877Y-49567D01*
G01X472077Y-57688D02*
Y-49672D01*
G01X470877Y-49567D02*
Y-57677D01*
G01X461820Y-47477D02*
X484315Y63990D01*
G01X463297Y-46230D02*
X463000Y-47700D01*
G01X464163Y-41936D02*
X463866Y-43407D01*
G01X485508Y63832D02*
X464733Y-39113D01*
G01X461428Y-49705D02*
X461818Y-47492D01*
G01X463000Y-47700D02*
X462628Y-49810D01*
G01X461428Y-57801D02*
Y-49705D01*
G01X462628Y-49810D02*
Y-57639D01*
G01X451979Y-56336D02*
Y-57931D01*
G01X453179Y-56231D02*
Y-57890D01*
G01X451324Y-52624D02*
X451979Y-56336D01*
G01X452543Y-52624D02*
X453179Y-56231D01*
G01X452024Y-48655D02*
X451324Y-52624D01*
G01X453200Y-48900D02*
X452543Y-52624D01*
G01X478908Y66822D02*
X452024Y-48655D01*
G01X453540Y-47439D02*
X453200Y-48900D01*
G01X454533Y-43173D02*
X454193Y-44634D01*
G01X480132Y66785D02*
X455186Y-40368D01*
G01X453179Y-56231D02*
Y-57890D01*
G01X451979Y-56336D02*
Y-57931D01*
G01X452543Y-52624D02*
X453179Y-56231D01*
G01X451324Y-52624D02*
X451979Y-56336D01*
G01X453200Y-48900D02*
X452543Y-52624D01*
G01X452024Y-48655D02*
X451324Y-52624D01*
G01X453540Y-47439D02*
X453200Y-48900D01*
G01X478908Y66822D02*
X452024Y-48655D01*
G01X454533Y-43173D02*
X454193Y-44634D01*
G01X478908Y66822D02*
X452024Y-48655D01*
G01X480132Y66785D02*
X455186Y-40368D01*
G01X478908Y66822D02*
X452024Y-48655D01*
G01X440670Y-42638D02*
G03X439883Y-41850I-787J1D01*
G01X509597Y62113D02*
X490259Y173040D01*
G01X505703Y91440D02*
X496285Y145467D01*
G01X510800Y62200D02*
X505703Y91440D01*
G01X504432Y62673D02*
X485343Y170906D01*
G01X486479Y171376D02*
X505651Y62673D01*
G01X481308Y166396D02*
X499371Y63987D01*
G01X482444Y166866D02*
X500590Y63987D01*
G01X478345Y156130D02*
X494592Y63986D01*
G01X479527Y156338D02*
X495806Y64017D01*
G01X509597Y62113D02*
X490259Y173040D01*
G01X509597Y62113D02*
X490259Y173040D01*
G01X509597Y62113D02*
X490259Y173040D01*
G01X505703Y91440D02*
X496285Y145467D01*
G01X509597Y62113D02*
X490259Y173040D01*
G01X510800Y62200D02*
X505703Y91440D01*
G01X509597Y62113D02*
X490259Y173040D01*
G01X486479Y171376D02*
X505651Y62673D01*
G01X504432D02*
X485343Y170906D01*
G01X482444Y166866D02*
X500590Y63987D01*
G01X481308Y166396D02*
X499371Y63987D01*
G01X479527Y156338D02*
X495806Y64017D01*
G01X478345Y156130D02*
X494592Y63986D01*
G01X489581Y64729D02*
X489585Y64253D01*
G01X490786Y64166D02*
X490781Y64764D01*
G01X489521Y65068D02*
X489581Y64729D01*
G01X490790Y64785D02*
X490432Y66811D01*
G01X489092Y67493D02*
X489521Y65068D01*
G01X490790Y64785D02*
X490432Y66811D01*
G01X486081Y84573D02*
X489092Y67493D01*
G01X490432Y66811D02*
X474971Y154499D01*
G01X480898Y113973D02*
X486081Y84573D01*
G01X490432Y66811D02*
X474971Y154499D01*
G01X490432Y66811D02*
X474971Y154499D01*
G01X490432Y66811D02*
X474971Y154499D01*
G01X485532Y64204D02*
X485508Y63832D01*
G01X484315Y63990D02*
X484333Y64261D01*
G01X474562Y128823D02*
X485543Y64589D01*
G01X484340Y64504D02*
X468918Y154709D01*
G01X484340Y64504D02*
X468918Y154709D01*
G01X484340Y64504D02*
X468918Y154709D01*
G01X490432Y66811D02*
X474971Y154499D01*
G01X486081Y84573D02*
X489092Y67493D01*
G01X480898Y113973D02*
X486081Y84573D01*
G01X490790Y64785D02*
X490432Y66811D01*
G01X489521Y65068D02*
X489581Y64729D01*
G01X489092Y67493D02*
X489521Y65068D01*
G01X490786Y64166D02*
X490781Y64764D01*
G01X489581Y64729D02*
X489585Y64253D01*
G01X484340Y64504D02*
X468918Y154709D01*
G01X474562Y128823D02*
X485543Y64589D01*
G01X484315Y63990D02*
X484333Y64261D01*
G01X485532Y64204D02*
X485508Y63832D01*
G01X464217Y152684D02*
X478908Y66822D01*
G01X465355Y153152D02*
X480132Y66785D01*
G01X465355Y153152D02*
X480132Y66785D01*
G01X464217Y152684D02*
X478908Y66822D01*
G01X494119Y178338D02*
X487608Y187637D01*
G01X488470Y188499D02*
X495255Y178808D01*
G01X495831Y168630D02*
X494119Y178338D01*
G01X495255Y178808D02*
X496814Y169968D01*
G01X514511Y62698D02*
X495831Y168628D01*
G01X496814Y169968D02*
X515730Y62698D01*
G01X496814Y169968D02*
X515730Y62698D01*
G01X514511D02*
X495831Y168628D01*
G01X495255Y178808D02*
X496814Y169968D01*
G01X495831Y168630D02*
X494119Y178338D01*
G01X488470Y188499D02*
X495255Y178808D01*
G01X494119Y178338D02*
X487608Y187637D01*
G01X490259Y173040D02*
X483538Y182638D01*
G01X490157Y175280D02*
X484400Y183500D01*
G01X490392Y174944D02*
X490157Y175280D01*
G01X491396Y173510D02*
X490392Y174944D01*
G01X491440Y173259D02*
X491396Y173510D01*
G01X491929Y170457D02*
X491440Y173259D01*
G01X496285Y145467D02*
X491929Y170457D01*
G01X479438Y179338D02*
X467134Y187954D01*
G01X485343Y170906D02*
X479438Y179338D01*
G01X480300Y180200D02*
X486479Y171376D01*
G01X474138Y176638D02*
X481308Y166396D01*
G01X475000Y177500D02*
X482444Y166866D01*
G01X464766Y183201D02*
X474138Y176638D01*
G01X465236Y184337D02*
X475000Y177500D01*
G01X477405Y161460D02*
X478345Y156130D01*
G01X479303Y157610D02*
X479527Y156338D01*
G01X478541Y161930D02*
X479303Y157610D01*
G01X468738Y173838D02*
X477405Y161460D01*
G01X469600Y174700D02*
X478541Y161930D01*
G01X461825Y178679D02*
X468738Y173838D01*
G01X462295Y179815D02*
X469600Y174700D01*
G01X490157Y175280D02*
X484400Y183500D01*
G01X490259Y173040D02*
X483538Y182638D01*
G01X490392Y174944D02*
X490157Y175280D01*
G01X490259Y173040D02*
X483538Y182638D01*
G01X491396Y173510D02*
X490392Y174944D01*
G01X490259Y173040D02*
X483538Y182638D01*
G01X491440Y173259D02*
X491396Y173510D01*
G01X491929Y170457D02*
X491440Y173259D01*
G01X496285Y145467D02*
X491929Y170457D01*
G01X480300Y180200D02*
X486479Y171376D01*
G01X485343Y170906D02*
X479438Y179338D01*
G01D02*
X467134Y187954D01*
G01X475000Y177500D02*
X482444Y166866D01*
G01X474138Y176638D02*
X481308Y166396D01*
G01X465236Y184337D02*
X475000Y177500D01*
G01X464766Y183201D02*
X474138Y176638D01*
G01X479303Y157610D02*
X479527Y156338D01*
G01X477405Y161460D02*
X478345Y156130D01*
G01X478541Y161930D02*
X479303Y157610D01*
G01X477405Y161460D02*
X478345Y156130D01*
G01X469600Y174700D02*
X478541Y161930D01*
G01X468738Y173838D02*
X477405Y161460D01*
G01X462295Y179815D02*
X469600Y174700D01*
G01X461825Y178679D02*
X468738Y173838D01*
G01X474319Y151286D02*
X480897Y113973D01*
G01X473789Y154291D02*
X474318Y151286D01*
G01X473598Y155376D02*
X473789Y154291D01*
G01X474971Y154499D02*
X474331Y158131D01*
G01X473195Y157661D02*
X473597Y155376D01*
G01X474971Y154499D02*
X474331Y158131D01*
G01X466138Y167738D02*
X473195Y157661D01*
G01X474331Y158131D02*
X467000Y168600D01*
G01X459128Y172647D02*
X466138Y167738D01*
G01X467000Y168600D02*
X459598Y173783D01*
G01X470277Y153885D02*
X474562Y128823D01*
G01X470054Y155179D02*
X470277Y153885D01*
G01X464873Y162579D02*
X470054Y155179D01*
G01X468918Y154709D02*
X464011Y161717D01*
G01X457550Y167707D02*
X464873Y162579D01*
G01X464011Y161717D02*
X457080Y166571D01*
G01X467000Y168600D02*
X459598Y173783D01*
G01X459128Y172647D02*
X466138Y167738D01*
G01X474331Y158131D02*
X467000Y168600D01*
G01X466138Y167738D02*
X473195Y157661D01*
G01X474971Y154499D02*
X474331Y158131D01*
G01X473598Y155376D02*
X473789Y154291D01*
G01X473195Y157661D02*
X473597Y155376D01*
G01X474319Y151286D02*
X480897Y113973D01*
G01X473789Y154291D02*
X474318Y151286D01*
G01X464011Y161717D02*
X457080Y166571D01*
G01X457550Y167707D02*
X464873Y162579D01*
G01X468918Y154709D02*
X464011Y161717D01*
G01X464873Y162579D02*
X470054Y155179D01*
G01X470277Y153885D02*
X474562Y128823D01*
G01X470054Y155179D02*
X470277Y153885D01*
G01X461531Y156519D02*
X464215Y152687D01*
G01X464206Y154792D02*
X465355Y153152D01*
G01X461565Y158563D02*
X464206Y154792D01*
G01X460703Y157701D02*
X461531Y156519D01*
G01X461565Y158563D02*
X464206Y154792D01*
G01X455229Y161536D02*
X460703Y157701D01*
G01X455699Y162672D02*
X461565Y158563D01*
G01X464206Y154792D02*
X465355Y153152D01*
G01X461531Y156519D02*
X464215Y152687D01*
G01X461565Y158563D02*
X464206Y154792D01*
G01X461531Y156519D02*
X464215Y152687D01*
G01X460703Y157701D02*
X461531Y156519D01*
G01X455699Y162672D02*
X461565Y158563D01*
G01X455229Y161536D02*
X460703Y157701D01*
G01X427342Y151385D02*
X427341D01*
G01X428528Y125240D02*
X428514D01*
G01X427667Y126103D02*
X427665Y126101D01*
G01X428563Y127383D02*
X427667Y126103D01*
G01X429699Y126913D02*
X428529Y125241D01*
G01X428840Y128956D02*
X428563Y127383D01*
G01X430040Y128851D02*
X429699Y126913D01*
G01X428840Y130723D02*
Y128956D01*
G01X430040Y130722D02*
Y128851D01*
G01X430234Y134089D02*
G03X428840Y130723I3367J-3366D01*
G01X431083Y133240D02*
G03X430040Y130722I2518J-2518D01*
G01X432065Y135920D02*
X430234Y134089D01*
G01X432914Y135071D02*
X431083Y133240D01*
G01X432777Y137640D02*
G02X432065Y135920I-2432J0D01*
G01X433978Y137640D02*
G02X432914Y135071I-3633J0D01*
G01X432778Y139712D02*
Y137639D01*
G01X433978Y139713D02*
Y137640D01*
G01X433521Y141511D02*
G03X432778Y139712I1800J-1796D01*
G01X434371Y140662D02*
G03X433978Y139713I949J-949D01*
G01X435084Y143074D02*
X433521Y141511D01*
G01X435933Y142225D02*
X434371Y140662D01*
G01X437009Y143870D02*
G03X435084Y143074I-2J-2722D01*
G01X437009Y142670D02*
G03X435933Y142225I-1J-1521D01*
G01X440712Y147573D02*
G02X437009Y143870I-3703J0D01*
G01X441912Y147573D02*
G02X437009Y142670I-4903J0D01*
G01X440712Y149395D02*
Y147573D01*
G01X441912Y149396D02*
Y147573D01*
G01X441949Y152157D02*
G03X440712Y149395I2460J-2760D01*
G01X442643Y151161D02*
G03X441912Y149396I1765J-1765D01*
G01X442553Y152458D02*
X441949Y152157D01*
G01X443091Y151385D02*
X442643Y151161D01*
G01X443092Y151385D02*
X443091D01*
G01X442554Y152458D02*
X442553D01*
G01X443091Y151385D02*
X442643Y151161D01*
G01X427342Y151385D02*
X427341D01*
G01X427667Y126103D02*
X427665Y126101D01*
G01X428528Y125240D02*
X428514D01*
G01X429699Y126913D02*
X428529Y125241D01*
G01X428563Y127383D02*
X427667Y126103D01*
G01X430040Y128851D02*
X429699Y126913D01*
G01X428840Y128956D02*
X428563Y127383D01*
G01X430040Y130722D02*
Y128851D01*
G01X428840Y130723D02*
Y128956D01*
G01X431083Y133240D02*
G03X430040Y130722I2518J-2518D01*
G01X430234Y134089D02*
G03X428840Y130723I3367J-3366D01*
G01X432914Y135071D02*
X431083Y133240D01*
G01X432065Y135920D02*
X430234Y134089D01*
G01X433978Y137640D02*
G02X432914Y135071I-3633J0D01*
G01X432777Y137640D02*
G02X432065Y135920I-2432J0D01*
G01X433978Y139713D02*
Y137640D01*
G01X432778Y139712D02*
Y137639D01*
G01X434371Y140662D02*
G03X433978Y139713I949J-949D01*
G01X433521Y141511D02*
G03X432778Y139712I1800J-1796D01*
G01X435933Y142225D02*
X434371Y140662D01*
G01X435084Y143074D02*
X433521Y141511D01*
G01X437009Y142670D02*
G03X435933Y142225I-1J-1521D01*
G01X437009Y143870D02*
G03X435084Y143074I-2J-2722D01*
G01X441912Y147573D02*
G02X437009Y142670I-4903J0D01*
G01X440712Y147573D02*
G02X437009Y143870I-3703J0D01*
G01X441912Y149396D02*
Y147573D01*
G01X440712Y149395D02*
Y147573D01*
G01X442643Y151161D02*
G03X441912Y149396I1765J-1765D01*
G01X441949Y152157D02*
G03X440712Y149395I2460J-2760D01*
G01X443091Y151385D02*
X442643Y151161D01*
G01X442553Y152458D02*
X441949Y152157D01*
G01X442554Y152458D02*
X442553D01*
G01X443092Y151385D02*
X443091D01*
G01X442553Y152458D02*
X441949Y152157D01*
G01X442547Y232360D02*
X442549D01*
G01X443086Y231287D02*
X442118Y230803D01*
G01X441443Y231808D02*
X442547Y232360D01*
G01X443086Y231287D02*
X442118Y230803D01*
G01X443087Y231287D02*
X443086D01*
G01X440648Y230150D02*
G02X441443Y231808I2122J2D01*
G01X442118Y230803D02*
G03X441848Y230151I652J-652D01*
G01X440648Y224725D02*
Y230150D01*
G01X441848Y230151D02*
Y224725D01*
G01X441059Y217306D02*
G02X440648Y224725I66709J7416D01*
G01X441848D02*
G03X442252Y217438I65920J0D01*
G01X443075Y214091D02*
G02X441059Y217306I2321J3695D01*
G01X442252Y217438D02*
G03X443714Y215107I3144J348D01*
G01X444328Y211914D02*
G03X443075Y214091I-2683J-95D01*
G01X443714Y215107D02*
G02X445528Y211956I-2068J-3288D01*
G01X444404Y209743D02*
X444328Y211914D01*
G01X445528Y211956D02*
X445601Y209869D01*
G01X445034Y206172D02*
X444404Y209743D01*
G01X445601Y209869D02*
X446170Y206642D01*
G01X446531Y204033D02*
X445034Y206172D01*
G01X446170Y206642D02*
X447393Y204895D01*
G01X450192Y201470D02*
X446531Y204033D01*
G01X447393Y204895D02*
X450662Y202606D01*
G01X473786Y197316D02*
X450192Y201470D01*
G01X450662Y202606D02*
X474256Y198452D01*
G01X487608Y187637D02*
X473786Y197316D01*
G01X474256Y198452D02*
X488470Y188499D01*
G01X474256Y198452D02*
X488470Y188499D01*
G01X487608Y187637D02*
X473786Y197316D01*
G01X450662Y202606D02*
X474256Y198452D01*
G01X473786Y197316D02*
X450192Y201470D01*
G01X447393Y204895D02*
X450662Y202606D01*
G01X450192Y201470D02*
X446531Y204033D01*
G01X446170Y206642D02*
X447393Y204895D01*
G01X446531Y204033D02*
X445034Y206172D01*
G01X445601Y209869D02*
X446170Y206642D01*
G01X445034Y206172D02*
X444404Y209743D01*
G01X445528Y211956D02*
X445601Y209869D01*
G01X444404Y209743D02*
X444328Y211914D01*
G01X443714Y215107D02*
G02X445528Y211956I-2068J-3288D01*
G01X444328Y211914D02*
G03X443075Y214091I-2683J-95D01*
G01X442252Y217438D02*
G03X443714Y215107I3144J348D01*
G01X443075Y214091D02*
G02X441059Y217306I2321J3695D01*
G01X441848Y224725D02*
G03X442252Y217438I65920J0D01*
G01X441059Y217306D02*
G02X440648Y224725I66709J7416D01*
G01X441848Y230151D02*
Y224725D01*
G01X440648D02*
Y230150D01*
G01X442118Y230803D02*
G03X441848Y230151I652J-652D01*
G01X440648Y230150D02*
G02X441443Y231808I2122J2D01*
G01X443086Y231287D02*
X442118Y230803D01*
G01X442547Y232360D02*
X442549D01*
G01X441443Y231808D02*
X442547Y232360D01*
G01X443087Y231287D02*
X443086D01*
G01X441443Y231808D02*
X442547Y232360D01*
G01X427341Y231287D02*
X427342D01*
G01X428583Y211914D02*
G03X427330Y214091I-2683J-95D01*
G01X429783Y211956D02*
G03X427969Y215107I-3882J-137D01*
G01X428660Y209726D02*
X428583Y211914D01*
G01X429856Y209869D02*
X429783Y211956D01*
G01X429074Y207715D02*
X428660Y209726D01*
G01X430200Y208200D02*
X429856Y209869D01*
G01X431452Y204317D02*
X429074Y207715D01*
G01X432378Y205089D02*
X430200Y208200D01*
G01X432013Y203751D02*
X431452Y204317D01*
G01X432790Y204672D02*
X432378Y205089D01*
G01X440143Y198058D02*
X432013Y203751D01*
G01X440613Y199194D02*
X432790Y204672D01*
G01X468710Y193021D02*
X440143Y198058D01*
G01X469180Y194157D02*
X440613Y199194D01*
G01X483538Y182638D02*
X468710Y193021D01*
G01X484400Y183500D02*
X469180Y194157D01*
G01X433868Y193820D02*
X430991Y194327D01*
G01X431461Y195463D02*
X434338Y194956D01*
G01X467134Y187954D02*
X433868Y193820D01*
G01X434338Y194956D02*
X467604Y189090D01*
G01D02*
X480300Y180200D01*
G01X427341Y231287D02*
X427342D01*
G01X429783Y211956D02*
G03X427969Y215107I-3882J-137D01*
G01X428583Y211914D02*
G03X427330Y214091I-2683J-95D01*
G01X429856Y209869D02*
X429783Y211956D01*
G01X428660Y209726D02*
X428583Y211914D01*
G01X430200Y208200D02*
X429856Y209869D01*
G01X429074Y207715D02*
X428660Y209726D01*
G01X432378Y205089D02*
X430200Y208200D01*
G01X431452Y204317D02*
X429074Y207715D01*
G01X432790Y204672D02*
X432378Y205089D01*
G01X432013Y203751D02*
X431452Y204317D01*
G01X440613Y199194D02*
X432790Y204672D01*
G01X440143Y198058D02*
X432013Y203751D01*
G01X469180Y194157D02*
X440613Y199194D01*
G01X468710Y193021D02*
X440143Y198058D01*
G01X484400Y183500D02*
X469180Y194157D01*
G01X483538Y182638D02*
X468710Y193021D01*
G01X467604Y189090D02*
X480300Y180200D01*
G01X434338Y194956D02*
X467604Y189090D01*
G01X467134Y187954D02*
X433868Y193820D01*
G01X431461Y195463D02*
X434338Y194956D01*
G01X433868Y193820D02*
X430991Y194327D01*
G01X428504Y544723D02*
Y563227D01*
G01Y544723D02*
G03X437953I4724J0D01*
G01Y563227D02*
Y544723D01*
G01X428505Y544724D02*
Y563228D01*
G01Y544724D02*
G03X437954I4725J0D01*
G01Y563228D02*
Y544724D01*
G01X439922Y565196D02*
X437954Y563228D01*
G01X540828Y565196D02*
X439922D01*
G01X547954Y-73346D02*
X622403D01*
G01X547954D02*
Y-7874D01*
G01X540080Y-71378D02*
Y-3937D01*
G01X538111Y-73346D02*
X540080Y-71378D01*
G01X514199Y-31884D02*
X514521Y60983D01*
G01X515721Y60980D02*
X515400Y-31800D01*
G01X515803Y-43069D02*
X514199Y-31884D01*
G01X515400Y-31800D02*
X516989Y-42879D01*
G01X518121Y-56210D02*
X515807Y-43087D01*
G01X518898Y-53706D02*
X519321Y-56105D01*
G01X518137Y-49393D02*
X518398Y-50870D01*
G01X516989Y-42879D02*
X517637Y-46557D01*
G01X518121Y-57805D02*
Y-56210D01*
G01X519321Y-56105D02*
Y-57832D01*
G01Y-56105D02*
Y-57832D01*
G01X518121Y-57805D02*
Y-56210D01*
G01X518898Y-53706D02*
X519321Y-56105D01*
G01X518121Y-56210D02*
X515807Y-43087D01*
G01X518137Y-49393D02*
X518398Y-50870D01*
G01X518121Y-56210D02*
X515807Y-43087D01*
G01X516989Y-42879D02*
X517637Y-46557D01*
G01X518121Y-56210D02*
X515807Y-43087D01*
G01X515400Y-31800D02*
X516989Y-42879D01*
G01X515803Y-43069D02*
X514199Y-31884D01*
G01X515721Y60980D02*
X515400Y-31800D01*
G01X514199Y-31884D02*
X514521Y60983D01*
G01X507824Y-45035D02*
X510800Y62200D01*
G01X508085Y-46512D02*
X507824Y-45035D01*
G01X508845Y-50826D02*
X508585Y-49348D01*
G01X509747Y-55936D02*
X509346Y-53662D01*
G01X508593Y-56307D02*
X508565Y-56144D01*
G01X509747Y-55936D02*
X509346Y-53662D01*
G01X508672Y-58014D02*
X508593Y-56307D01*
G01X509872Y-57983D02*
X509778Y-55934D01*
G01X507824Y-45035D02*
X510800Y62200D01*
G01X508085Y-46512D02*
X507824Y-45035D01*
G01X508845Y-50826D02*
X508585Y-49348D01*
G01X509747Y-55936D02*
X509346Y-53662D01*
G01X508593Y-56307D02*
X508565Y-56144D01*
G01X509872Y-57983D02*
X509778Y-55934D01*
G01X508672Y-58014D02*
X508593Y-56307D01*
G01X558662Y9505D02*
Y155374D01*
G01X557509Y6721D02*
G03X558662Y9505I-2784J2784D01*
G01X551942Y1153D02*
X557509Y6721D01*
G01X549158Y0D02*
G03X551942Y1153I0J3937D01*
G01X544017Y0D02*
X549158D01*
G01X544017D02*
G03X540080Y-3937I0J-3937D01*
G01X547954Y-7874D02*
X549158D01*
G01Y0D02*
G03X551942Y1153I0J3937D01*
G01X549158Y-7875D02*
G03X557510Y-4415I0J11811D01*
G01X551942Y1153D02*
X557509Y6721D01*
G01X557510Y-4414D02*
X563077Y1154D01*
G01X557509Y6721D02*
G03X558662Y9505I-2784J2784D01*
G01X563077Y1153D02*
G03X566536Y9507I-8352J8351D01*
G01X558662Y9505D02*
Y155374D01*
G01X566536Y9505D02*
Y18655D01*
G01D02*
G03X558662I-3937J-1D01*
G01X514521Y60983D02*
Y62688D01*
G01X515721D02*
Y60980D01*
G01X515730Y62698D02*
Y62697D01*
G01X515721Y62688D02*
Y60980D01*
G01X514521Y60983D02*
Y62688D01*
G01X515730Y62698D02*
Y62697D01*
G01X514521Y60983D02*
Y62688D01*
G01X558662Y49363D02*
G03X566536I3937J0D01*
G01D02*
Y151437D01*
G01X562599Y159311D02*
X611812D01*
G01X562599D02*
G03X558662Y155374I0J-3937D01*
G01X562599Y159311D02*
G03X558662Y155374I0J-3937D01*
G01X562599Y159311D02*
X611812D01*
G01X566536Y151437D02*
X574076D01*
G01D02*
G03Y159311I0J3937D01*
G01X564353Y249862D02*
G03Y241988I0J-3937D01*
G01X521844D02*
G03Y249862I0J3937D01*
G01X542796Y495787D02*
Y563228D01*
G01Y495787D02*
G03X546733Y491850I3937J0D01*
G01X606244D02*
X546733D01*
G01X606244D02*
X546733D01*
G01X542796Y495787D02*
G03X546733Y491850I3937J0D01*
G01X550670Y499724D02*
Y563622D01*
G01X570124Y491850D02*
G03Y499724I0J3937D01*
G01D02*
X550670D01*
G01Y565196D02*
X622403D01*
G01X542796Y563228D02*
X540828Y565196D01*
G01X550670Y563622D02*
Y565196D01*
G01X622403Y-73346D02*
G03X637403Y-58346I0J15000D01*
G01Y253799D02*
Y-58346D01*
G01X615749Y163248D02*
Y228546D01*
G01X611812Y159311D02*
G03X615749Y163248I0J3937D01*
G01X611812Y159311D02*
G03X615749Y163248I0J3937D01*
G01X611812Y151437D02*
G03X623623Y163248I0J11811D01*
G01X615749D02*
Y228546D01*
G01X623623Y163248D02*
Y228546D01*
G01X604785Y159311D02*
G03Y151437I0J-3937D01*
G01D02*
X611812D01*
G01X615749Y253799D02*
Y482345D01*
G01X611812Y249862D02*
G03X615749Y253799I0J3937D01*
G01X605091Y240835D02*
G03X602307Y241988I-2784J-2784D01*
G01X614596Y231330D02*
X605091Y240835D01*
G01X615749Y228546D02*
G03X614596Y231330I-3937J0D01*
G01X615749Y228546D02*
G03X614596Y231330I-3937J0D01*
G01D02*
X605091Y240835D01*
G01D02*
G03X602307Y241988I-2784J-2784D01*
G01X611812Y249862D02*
G03X615749Y253799I0J3937D01*
G01D02*
Y482345D01*
G01X623623Y253799D02*
Y274659D01*
G01X637403Y253799D02*
Y482345D01*
G01X623623Y228546D02*
Y253799D01*
G01Y274659D02*
G03X615749I-3937J0D01*
G01Y305368D02*
G03X623623I3937J0D01*
G01D02*
Y410289D01*
G01D02*
G03X615749I-3937J0D01*
G01X609028Y490697D02*
G03X606244Y491850I-2784J-2784D01*
G01X614596Y485129D02*
X609028Y490697D01*
G01X615749Y482345D02*
G03X614596Y485129I-3937J0D01*
G01X615749Y482345D02*
G03X614596Y485129I-3937J0D01*
G01X623623Y482345D02*
G03X620164Y490697I-11811J1D01*
G01X614596Y485129D02*
X609028Y490697D01*
G01X620164D02*
X614596Y496265D01*
G01X609028Y490697D02*
G03X606244Y491850I-2784J-2784D01*
G01X614596Y496265D02*
G03X606244Y499724I-8351J-8352D01*
G01D02*
X600833D01*
G01X637403Y482345D02*
Y550196D01*
G01X600833Y499724D02*
G03Y491850I0J-3937D01*
G01X615749Y440998D02*
G03X623623I3937J0D01*
G01D02*
Y482345D01*
G01X637403Y550196D02*
G03X622403Y565196I-15000J0D01*
G54D12*
G01X-15353Y-106096D02*
Y-123596D01*
G01X-20375Y-106096D02*
X-10331D01*
G01X-1565Y-123596D02*
Y-106096D01*
G01Y-114554D02*
X-473Y-113096D01*
X619Y-112221D01*
X2365Y-111930D01*
X3675Y-112221D01*
X5204Y-113388D01*
X5859Y-115138D01*
Y-123596D01*
G01X19647Y-111930D02*
Y-123596D01*
G01Y-107263D02*
X19210Y-106971D01*
Y-106388D01*
X19647Y-106096D01*
X20084Y-106388D01*
Y-106971D01*
X19647Y-107263D01*
G01X33872Y-121555D02*
X34964Y-122721D01*
X36492Y-123596D01*
X37802D01*
X39112Y-123013D01*
X39985Y-122138D01*
X40422Y-120972D01*
X40204Y-119221D01*
X39330Y-118346D01*
X35400Y-116596D01*
X34527Y-114554D01*
X34964Y-113096D01*
X35837Y-112221D01*
X37147Y-111930D01*
X38457Y-112221D01*
X39767Y-113096D01*
G01X69090Y-127971D02*
X70619Y-129138D01*
X72365Y-129429D01*
X73893Y-129138D01*
X75204Y-127680D01*
X76077Y-125638D01*
Y-111930D01*
G01Y-114263D02*
X75204Y-113096D01*
X73893Y-112221D01*
X72365Y-111930D01*
X70619Y-112513D01*
X69527Y-113679D01*
X68653Y-115721D01*
X68217Y-117763D01*
X68435Y-119513D01*
X69309Y-121555D01*
X70619Y-123013D01*
X72365Y-123596D01*
X73675Y-123304D01*
X75204Y-122138D01*
X76077Y-120972D01*
G01X86372Y-115721D02*
X93359D01*
X92704Y-113679D01*
X91612Y-112513D01*
X90084Y-111930D01*
X88555Y-112221D01*
X87245Y-113096D01*
X86372Y-115138D01*
X85935Y-116888D01*
Y-118638D01*
X86372Y-120388D01*
X87464Y-122138D01*
X88774Y-123304D01*
X90302Y-123596D01*
X91830Y-123013D01*
X93359Y-121263D01*
G01X104090Y-123596D02*
Y-111930D01*
G01Y-114263D02*
X105182Y-113096D01*
X106274Y-112221D01*
X107802Y-111930D01*
X108893Y-112221D01*
X110204Y-113096D01*
G01X120717Y-123596D02*
Y-106096D01*
G01Y-114846D02*
X121809Y-113096D01*
X123119Y-112221D01*
X124429Y-111930D01*
X126393Y-112513D01*
X127704Y-113679D01*
X128577Y-115721D01*
Y-118054D01*
X128140Y-120388D01*
X127267Y-122138D01*
X125739Y-123304D01*
X124429Y-123596D01*
X123119Y-123304D01*
X121809Y-122430D01*
X120717Y-120972D01*
G01X138872Y-115721D02*
X145859D01*
X145204Y-113679D01*
X144112Y-112513D01*
X142584Y-111930D01*
X141055Y-112221D01*
X139745Y-113096D01*
X138872Y-115138D01*
X138435Y-116888D01*
Y-118638D01*
X138872Y-120388D01*
X139964Y-122138D01*
X141274Y-123304D01*
X142802Y-123596D01*
X144330Y-123013D01*
X145859Y-121263D01*
G01X156590Y-123596D02*
Y-111930D01*
G01Y-114263D02*
X157682Y-113096D01*
X158774Y-112221D01*
X160302Y-111930D01*
X161393Y-112221D01*
X162704Y-113096D01*
G01X194647Y-111930D02*
Y-123596D01*
G01Y-107263D02*
X194210Y-106971D01*
Y-106388D01*
X194647Y-106096D01*
X195084Y-106388D01*
Y-106971D01*
X194647Y-107263D01*
G01X208872Y-121555D02*
X209964Y-122721D01*
X211492Y-123596D01*
X212802D01*
X214112Y-123013D01*
X214985Y-122138D01*
X215422Y-120972D01*
X215204Y-119221D01*
X214330Y-118346D01*
X210400Y-116596D01*
X209527Y-114554D01*
X209964Y-113096D01*
X210837Y-112221D01*
X212147Y-111930D01*
X213457Y-112221D01*
X214767Y-113096D01*
G01X243653Y-127971D02*
X245182Y-129138D01*
X246492Y-129429D01*
X248239Y-128846D01*
X249549Y-127388D01*
X250204Y-124762D01*
Y-111930D01*
G01Y-107263D02*
X249767Y-106971D01*
Y-106388D01*
X250204Y-106096D01*
X250640Y-106388D01*
Y-106971D01*
X250204Y-107263D01*
G01X260935Y-111930D02*
Y-120096D01*
X261809Y-122138D01*
X263119Y-123304D01*
X264647Y-123596D01*
X266175Y-123304D01*
X267485Y-122138D01*
X268359Y-120096D01*
G01Y-123596D02*
Y-111930D01*
G01X278872Y-121555D02*
X279964Y-122721D01*
X281492Y-123596D01*
X282802D01*
X284112Y-123013D01*
X284985Y-122138D01*
X285422Y-120972D01*
X285204Y-119221D01*
X284330Y-118346D01*
X280400Y-116596D01*
X279527Y-114554D01*
X279964Y-113096D01*
X280837Y-112221D01*
X282147Y-111930D01*
X283457Y-112221D01*
X284767Y-113096D01*
G01X299647Y-106096D02*
Y-123596D01*
G01X296590Y-111930D02*
X302704D01*
G01X333337Y-123596D02*
Y-108721D01*
X333774Y-107263D01*
X334647Y-106388D01*
X335957Y-106096D01*
X337267Y-106679D01*
X337922Y-108138D01*
G01X335302Y-113096D02*
X330935D01*
G01X352147Y-123596D02*
X350837Y-123304D01*
X349527Y-122138D01*
X348653Y-120096D01*
X348217Y-117763D01*
X348653Y-115429D01*
X349527Y-113388D01*
X350837Y-112221D01*
X352147Y-111930D01*
X353457Y-112221D01*
X354767Y-113388D01*
X355640Y-115429D01*
X355859Y-117763D01*
X355640Y-120096D01*
X354767Y-122138D01*
X353457Y-123304D01*
X352147Y-123596D01*
G01X366590D02*
Y-111930D01*
G01Y-114263D02*
X367682Y-113096D01*
X368774Y-112221D01*
X370302Y-111930D01*
X371393Y-112221D01*
X372704Y-113096D01*
G01X400062Y-128846D02*
X401372Y-129429D01*
X403119Y-128846D01*
X404210Y-127680D01*
X405084Y-126221D01*
X406393Y-121555D01*
X409232Y-111930D01*
G01X402245D02*
X406393Y-121555D01*
G01X422147Y-123596D02*
X420837Y-123304D01*
X419527Y-122138D01*
X418653Y-120096D01*
X418217Y-117763D01*
X418653Y-115429D01*
X419527Y-113388D01*
X420837Y-112221D01*
X422147Y-111930D01*
X423457Y-112221D01*
X424767Y-113388D01*
X425640Y-115429D01*
X425859Y-117763D01*
X425640Y-120096D01*
X424767Y-122138D01*
X423457Y-123304D01*
X422147Y-123596D01*
G01X435935Y-111930D02*
Y-120096D01*
X436809Y-122138D01*
X438119Y-123304D01*
X439647Y-123596D01*
X441175Y-123304D01*
X442485Y-122138D01*
X443359Y-120096D01*
G01Y-123596D02*
Y-111930D01*
G01X454090Y-123596D02*
Y-111930D01*
G01Y-114263D02*
X455182Y-113096D01*
X456274Y-112221D01*
X457802Y-111930D01*
X458893Y-112221D01*
X460204Y-113096D01*
G01X489090Y-123596D02*
Y-111930D01*
G01Y-114263D02*
X490182Y-113096D01*
X491274Y-112221D01*
X492802Y-111930D01*
X493893Y-112221D01*
X495204Y-113096D01*
G01X506372Y-115721D02*
X513359D01*
X512704Y-113679D01*
X511612Y-112513D01*
X510084Y-111930D01*
X508555Y-112221D01*
X507245Y-113096D01*
X506372Y-115138D01*
X505935Y-116888D01*
Y-118638D01*
X506372Y-120388D01*
X507464Y-122138D01*
X508774Y-123304D01*
X510302Y-123596D01*
X511830Y-123013D01*
X513359Y-121263D01*
G01X525837Y-123596D02*
Y-108721D01*
X526274Y-107263D01*
X527147Y-106388D01*
X528457Y-106096D01*
X529767Y-106679D01*
X530422Y-108138D01*
G01X527802Y-113096D02*
X523435D01*
G01X541372Y-115721D02*
X548359D01*
X547704Y-113679D01*
X546612Y-112513D01*
X545084Y-111930D01*
X543555Y-112221D01*
X542245Y-113096D01*
X541372Y-115138D01*
X540935Y-116888D01*
Y-118638D01*
X541372Y-120388D01*
X542464Y-122138D01*
X543774Y-123304D01*
X545302Y-123596D01*
X546830Y-123013D01*
X548359Y-121263D01*
G01X559090Y-123596D02*
Y-111930D01*
G01Y-114263D02*
X560182Y-113096D01*
X561274Y-112221D01*
X562802Y-111930D01*
X563893Y-112221D01*
X565204Y-113096D01*
G01X576372Y-115721D02*
X583359D01*
X582704Y-113679D01*
X581612Y-112513D01*
X580084Y-111930D01*
X578555Y-112221D01*
X577245Y-113096D01*
X576372Y-115138D01*
X575935Y-116888D01*
Y-118638D01*
X576372Y-120388D01*
X577464Y-122138D01*
X578774Y-123304D01*
X580302Y-123596D01*
X581830Y-123013D01*
X583359Y-121263D01*
G01X593435Y-123596D02*
Y-111930D01*
G01Y-114846D02*
X594309Y-113388D01*
X595619Y-112221D01*
X597365Y-111930D01*
X598893Y-112221D01*
X600204Y-113388D01*
X600859Y-115429D01*
Y-123596D01*
G01X618140Y-113388D02*
X616612Y-112221D01*
X615302Y-111930D01*
X613555Y-112513D01*
X612245Y-113679D01*
X611372Y-115721D01*
X611153Y-117763D01*
X611372Y-119805D01*
X612245Y-121555D01*
X613555Y-123013D01*
X615302Y-123596D01*
X616830Y-123013D01*
X618140Y-121846D01*
G01X628872Y-115721D02*
X635859D01*
X635204Y-113679D01*
X634112Y-112513D01*
X632584Y-111930D01*
X631055Y-112221D01*
X629745Y-113096D01*
X628872Y-115138D01*
X628435Y-116888D01*
Y-118638D01*
X628872Y-120388D01*
X629964Y-122138D01*
X631274Y-123304D01*
X632802Y-123596D01*
X634330Y-123013D01*
X635859Y-121263D01*
G01X667147Y-106096D02*
Y-123596D01*
G01X664090Y-111930D02*
X670204D01*
G01X684647Y-123596D02*
X683337Y-123304D01*
X682027Y-122138D01*
X681153Y-120096D01*
X680717Y-117763D01*
X681153Y-115429D01*
X682027Y-113388D01*
X683337Y-112221D01*
X684647Y-111930D01*
X685957Y-112221D01*
X687267Y-113388D01*
X688140Y-115429D01*
X688359Y-117763D01*
X688140Y-120096D01*
X687267Y-122138D01*
X685957Y-123304D01*
X684647Y-123596D01*
G01X718337D02*
Y-108721D01*
X718774Y-107263D01*
X719647Y-106388D01*
X720957Y-106096D01*
X722267Y-106679D01*
X722922Y-108138D01*
G01X720302Y-113096D02*
X715935D01*
G01X737147Y-111930D02*
Y-123596D01*
G01Y-107263D02*
X736710Y-106971D01*
Y-106388D01*
X737147Y-106096D01*
X737584Y-106388D01*
Y-106971D01*
X737147Y-107263D01*
G01X750935Y-123596D02*
Y-111930D01*
G01Y-114846D02*
X751809Y-113388D01*
X753119Y-112221D01*
X754865Y-111930D01*
X756393Y-112221D01*
X757704Y-113388D01*
X758359Y-115429D01*
Y-123596D01*
G01X776077Y-106096D02*
Y-123596D01*
G01Y-120972D02*
X775204Y-122430D01*
X773893Y-123304D01*
X772365Y-123596D01*
X770619Y-123013D01*
X769309Y-121555D01*
X768435Y-119805D01*
X768217Y-117763D01*
X768435Y-115721D01*
X769309Y-113971D01*
X770619Y-112513D01*
X772365Y-111930D01*
X773893Y-112221D01*
X774985Y-112805D01*
X776077Y-113971D01*
G01X807147Y-106096D02*
Y-123596D01*
G01X804090Y-111930D02*
X810204D01*
G01X820935Y-123596D02*
Y-106096D01*
G01Y-114554D02*
X822027Y-113096D01*
X823119Y-112221D01*
X824865Y-111930D01*
X826175Y-112221D01*
X827704Y-113388D01*
X828359Y-115138D01*
Y-123596D01*
G01X838872Y-115721D02*
X845859D01*
X845204Y-113679D01*
X844112Y-112513D01*
X842584Y-111930D01*
X841055Y-112221D01*
X839745Y-113096D01*
X838872Y-115138D01*
X838435Y-116888D01*
Y-118638D01*
X838872Y-120388D01*
X839964Y-122138D01*
X841274Y-123304D01*
X842802Y-123596D01*
X844330Y-123013D01*
X845859Y-121263D01*
G01X872344Y-123596D02*
Y-106096D01*
X876710D01*
X878457Y-106971D01*
X879767Y-108138D01*
X880859Y-109887D01*
X881732Y-111930D01*
X881950Y-114846D01*
X881732Y-117763D01*
X880859Y-119805D01*
X879767Y-121555D01*
X878457Y-122721D01*
X876710Y-123596D01*
X872344D01*
G01X890280D02*
Y-106096D01*
X895520D01*
X897267Y-106971D01*
X898577Y-109013D01*
X899014Y-111346D01*
X898577Y-113679D01*
X897485Y-115429D01*
X895520Y-116305D01*
X890280D01*
G01X929647Y-111930D02*
Y-123596D01*
G01Y-107263D02*
X929210Y-106971D01*
Y-106388D01*
X929647Y-106096D01*
X930084Y-106388D01*
Y-106971D01*
X929647Y-107263D01*
G01X940597Y-123596D02*
Y-111930D01*
G01Y-115138D02*
X941252Y-113679D01*
X942344Y-112513D01*
X943872Y-111930D01*
X945400Y-112513D01*
X946492Y-113679D01*
X947147Y-115138D01*
Y-123596D01*
G01Y-115138D02*
X947802Y-113679D01*
X948893Y-112513D01*
X950422Y-111930D01*
X951950Y-112513D01*
X953042Y-113679D01*
X953697Y-115429D01*
Y-123596D01*
G01X960717Y-129429D02*
Y-111930D01*
G01Y-114554D02*
X961809Y-113096D01*
X962900Y-112221D01*
X964647Y-111930D01*
X966175Y-112221D01*
X967704Y-113679D01*
X968359Y-115721D01*
X968577Y-117763D01*
X968359Y-119805D01*
X967704Y-121846D01*
X966393Y-123013D01*
X964647Y-123596D01*
X963119Y-123304D01*
X961590Y-122430D01*
X960717Y-121263D01*
G01X978872Y-115721D02*
X985859D01*
X985204Y-113679D01*
X984112Y-112513D01*
X982584Y-111930D01*
X981055Y-112221D01*
X979745Y-113096D01*
X978872Y-115138D01*
X978435Y-116888D01*
Y-118638D01*
X978872Y-120388D01*
X979964Y-122138D01*
X981274Y-123304D01*
X982802Y-123596D01*
X984330Y-123013D01*
X985859Y-121263D01*
G01X1003577Y-106096D02*
Y-123596D01*
G01Y-120972D02*
X1002704Y-122430D01*
X1001393Y-123304D01*
X999865Y-123596D01*
X998119Y-123013D01*
X996809Y-121555D01*
X995935Y-119805D01*
X995717Y-117763D01*
X995935Y-115721D01*
X996809Y-113971D01*
X998119Y-112513D01*
X999865Y-111930D01*
X1001393Y-112221D01*
X1002485Y-112805D01*
X1003577Y-113971D01*
G01X1021077Y-123596D02*
Y-111930D01*
G01Y-113971D02*
X1020204Y-112805D01*
X1018893Y-112221D01*
X1017365Y-111930D01*
X1015837Y-112513D01*
X1014527Y-113679D01*
X1013653Y-115429D01*
X1013217Y-117763D01*
X1013653Y-120096D01*
X1014527Y-121846D01*
X1015837Y-123013D01*
X1017365Y-123596D01*
X1018893Y-123304D01*
X1020204Y-122430D01*
X1021077Y-121263D01*
G01X1030935Y-123596D02*
Y-111930D01*
G01Y-114846D02*
X1031809Y-113388D01*
X1033119Y-112221D01*
X1034865Y-111930D01*
X1036393Y-112221D01*
X1037704Y-113388D01*
X1038359Y-115429D01*
Y-123596D01*
G01X1055640Y-113388D02*
X1054112Y-112221D01*
X1052802Y-111930D01*
X1051055Y-112513D01*
X1049745Y-113679D01*
X1048872Y-115721D01*
X1048653Y-117763D01*
X1048872Y-119805D01*
X1049745Y-121555D01*
X1051055Y-123013D01*
X1052802Y-123596D01*
X1054330Y-123013D01*
X1055640Y-121846D01*
G01X1066372Y-115721D02*
X1073359D01*
X1072704Y-113679D01*
X1071612Y-112513D01*
X1070084Y-111930D01*
X1068555Y-112221D01*
X1067245Y-113096D01*
X1066372Y-115138D01*
X1065935Y-116888D01*
Y-118638D01*
X1066372Y-120388D01*
X1067464Y-122138D01*
X1068774Y-123304D01*
X1070302Y-123596D01*
X1071830Y-123013D01*
X1073359Y-121263D01*
G01X1104647Y-106096D02*
Y-123596D01*
G01X1101590Y-111930D02*
X1107704D01*
G01X1119090Y-123596D02*
Y-111930D01*
G01Y-114263D02*
X1120182Y-113096D01*
X1121274Y-112221D01*
X1122802Y-111930D01*
X1123893Y-112221D01*
X1125204Y-113096D01*
G01X1143577Y-123596D02*
Y-111930D01*
G01Y-113971D02*
X1142704Y-112805D01*
X1141393Y-112221D01*
X1139865Y-111930D01*
X1138337Y-112513D01*
X1137027Y-113679D01*
X1136153Y-115429D01*
X1135717Y-117763D01*
X1136153Y-120096D01*
X1137027Y-121846D01*
X1138337Y-123013D01*
X1139865Y-123596D01*
X1141393Y-123304D01*
X1142704Y-122430D01*
X1143577Y-121263D01*
G01X1160640Y-113388D02*
X1159112Y-112221D01*
X1157802Y-111930D01*
X1156055Y-112513D01*
X1154745Y-113679D01*
X1153872Y-115721D01*
X1153653Y-117763D01*
X1153872Y-119805D01*
X1154745Y-121555D01*
X1156055Y-123013D01*
X1157802Y-123596D01*
X1159330Y-123013D01*
X1160640Y-121846D01*
G01X1171372Y-115721D02*
X1178359D01*
X1177704Y-113679D01*
X1176612Y-112513D01*
X1175084Y-111930D01*
X1173555Y-112221D01*
X1172245Y-113096D01*
X1171372Y-115138D01*
X1170935Y-116888D01*
Y-118638D01*
X1171372Y-120388D01*
X1172464Y-122138D01*
X1173774Y-123304D01*
X1175302Y-123596D01*
X1176830Y-123013D01*
X1178359Y-121263D01*
G01X1188872Y-121555D02*
X1189964Y-122721D01*
X1191492Y-123596D01*
X1192802D01*
X1194112Y-123013D01*
X1194985Y-122138D01*
X1195422Y-120972D01*
X1195204Y-119221D01*
X1194330Y-118346D01*
X1190400Y-116596D01*
X1189527Y-114554D01*
X1189964Y-113096D01*
X1190837Y-112221D01*
X1192147Y-111930D01*
X1193457Y-112221D01*
X1194767Y-113096D01*
G01X1227147Y-111930D02*
Y-123596D01*
G01Y-107263D02*
X1226710Y-106971D01*
Y-106388D01*
X1227147Y-106096D01*
X1227584Y-106388D01*
Y-106971D01*
X1227147Y-107263D01*
G01X1240935Y-123596D02*
Y-111930D01*
G01Y-114846D02*
X1241809Y-113388D01*
X1243119Y-112221D01*
X1244865Y-111930D01*
X1246393Y-112221D01*
X1247704Y-113388D01*
X1248359Y-115429D01*
Y-123596D01*
G01X1279647D02*
Y-106096D01*
G01X1301077Y-123596D02*
Y-111930D01*
G01Y-113971D02*
X1300204Y-112805D01*
X1298893Y-112221D01*
X1297365Y-111930D01*
X1295837Y-112513D01*
X1294527Y-113679D01*
X1293653Y-115429D01*
X1293217Y-117763D01*
X1293653Y-120096D01*
X1294527Y-121846D01*
X1295837Y-123013D01*
X1297365Y-123596D01*
X1298893Y-123304D01*
X1300204Y-122430D01*
X1301077Y-121263D01*
G01X1310062Y-128846D02*
X1311372Y-129429D01*
X1313119Y-128846D01*
X1314210Y-127680D01*
X1315084Y-126221D01*
X1316393Y-121555D01*
X1319232Y-111930D01*
G01X1312245D02*
X1316393Y-121555D01*
G01X1328872Y-115721D02*
X1335859D01*
X1335204Y-113679D01*
X1334112Y-112513D01*
X1332584Y-111930D01*
X1331055Y-112221D01*
X1329745Y-113096D01*
X1328872Y-115138D01*
X1328435Y-116888D01*
Y-118638D01*
X1328872Y-120388D01*
X1329964Y-122138D01*
X1331274Y-123304D01*
X1332802Y-123596D01*
X1334330Y-123013D01*
X1335859Y-121263D01*
G01X1346590Y-123596D02*
Y-111930D01*
G01Y-114263D02*
X1347682Y-113096D01*
X1348774Y-112221D01*
X1350302Y-111930D01*
X1351393Y-112221D01*
X1352704Y-113096D01*
G01X1380280Y-106096D02*
Y-123596D01*
X1389014D01*
G01X1397999Y-116305D02*
X1399527Y-114263D01*
X1400837Y-113096D01*
X1402584Y-112513D01*
X1404112Y-113096D01*
X1405204Y-114263D01*
X1406077Y-116013D01*
X1406295Y-118054D01*
X1406077Y-119805D01*
X1405204Y-121555D01*
X1403893Y-123013D01*
X1402365Y-123596D01*
X1400619Y-123013D01*
X1399090Y-121263D01*
X1398217Y-118638D01*
X1397999Y-115721D01*
X1398435Y-111930D01*
X1399090Y-109887D01*
X1400182Y-107846D01*
X1401710Y-106388D01*
X1403239Y-106096D01*
X1404767Y-106679D01*
X1405859Y-108138D01*
G01X1419647Y-124179D02*
X1419210Y-123888D01*
Y-123304D01*
X1419647Y-123013D01*
X1420084Y-123304D01*
Y-123888D01*
X1419647Y-124179D01*
G01X748903Y471246D02*
X750431Y471538D01*
X752178Y472412D01*
X753270Y473870D01*
X753706Y475913D01*
X753270Y477954D01*
X751960Y479704D01*
X749995Y480579D01*
X747811D01*
X746501Y481163D01*
X745409Y482621D01*
X744973Y484662D01*
X745628Y486704D01*
X747156Y488163D01*
X748903Y488746D01*
X750649Y488163D01*
X752178Y486704D01*
X752833Y484662D01*
X752396Y482621D01*
X751305Y481163D01*
X749995Y480579D01*
X747811D01*
X745846Y479704D01*
X744536Y477954D01*
X744100Y475913D01*
X744536Y473870D01*
X745628Y472412D01*
X747375Y471538D01*
X748903Y471246D01*
G01X761600Y473870D02*
X762909Y472412D01*
X764438Y471538D01*
X766403Y471246D01*
X768368Y471829D01*
X769896Y472996D01*
X770988Y475037D01*
X771206Y477371D01*
X770770Y479704D01*
X769678Y481163D01*
X768149Y482329D01*
X766621Y482621D01*
X765093Y482329D01*
X763128Y481163D01*
X763783Y488746D01*
X769678D01*
G01X783903Y470663D02*
X783466Y470954D01*
Y471538D01*
X783903Y471829D01*
X784340Y471538D01*
Y470954D01*
X783903Y470663D01*
G01X801403Y488746D02*
X799656Y488163D01*
X798346Y486704D01*
X797473Y484955D01*
X796818Y482621D01*
X796600Y479996D01*
X796818Y477371D01*
X797473Y475037D01*
X798346Y473287D01*
X799656Y471829D01*
X801403Y471246D01*
X803149Y471829D01*
X804460Y473287D01*
X805333Y475037D01*
X805988Y477371D01*
X806206Y479996D01*
X805988Y482621D01*
X805333Y484955D01*
X804460Y486704D01*
X803149Y488163D01*
X801403Y488746D01*
G01X735350Y436013D02*
X744956Y448846D01*
G01X740153Y451179D02*
Y433679D01*
G01X744956Y436013D02*
X735350Y448846D01*
G01X733603Y442429D02*
X746703D01*
G01X753941Y438637D02*
X755470Y437179D01*
X757216Y436596D01*
X758963Y437179D01*
X760491Y438929D01*
X761583Y441554D01*
X762020Y444179D01*
Y447387D01*
X761583Y450012D01*
X760491Y452346D01*
X759181Y453513D01*
X757653Y454096D01*
X755906Y453513D01*
X754596Y452346D01*
X753723Y450596D01*
X753286Y448262D01*
X753723Y446221D01*
X754815Y444179D01*
X756125Y443012D01*
X757653Y442721D01*
X759399Y443304D01*
X760710Y444763D01*
X762020Y447387D01*
G01X775153Y454096D02*
X773406Y453513D01*
X772096Y452054D01*
X771223Y450305D01*
X770568Y447971D01*
X770350Y445346D01*
X770568Y442721D01*
X771223Y440387D01*
X772096Y438637D01*
X773406Y437179D01*
X775153Y436596D01*
X776899Y437179D01*
X778210Y438637D01*
X779083Y440387D01*
X779738Y442721D01*
X779956Y445346D01*
X779738Y447971D01*
X779083Y450305D01*
X778210Y452054D01*
X776899Y453513D01*
X775153Y454096D01*
G01X792653Y436013D02*
X792216Y436304D01*
Y436888D01*
X792653Y437179D01*
X793090Y436888D01*
Y436304D01*
X792653Y436013D01*
G01X810153Y454096D02*
X808406Y453513D01*
X807096Y452054D01*
X806223Y450305D01*
X805568Y447971D01*
X805350Y445346D01*
X805568Y442721D01*
X806223Y440387D01*
X807096Y438637D01*
X808406Y437179D01*
X810153Y436596D01*
X811899Y437179D01*
X813210Y438637D01*
X814083Y440387D01*
X814738Y442721D01*
X814956Y445346D01*
X814738Y447971D01*
X814083Y450305D01*
X813210Y452054D01*
X811899Y453513D01*
X810153Y454096D01*
G01X689400Y540546D02*
Y558046D01*
X693766D01*
X695513Y557171D01*
X696823Y556004D01*
X697915Y554255D01*
X698788Y552212D01*
X699006Y549296D01*
X698788Y546379D01*
X697915Y544337D01*
X696823Y542587D01*
X695513Y541421D01*
X693766Y540546D01*
X689400D01*
G01X707336D02*
Y558046D01*
X712576D01*
X714323Y557171D01*
X715633Y555129D01*
X716070Y552796D01*
X715633Y550463D01*
X714541Y548713D01*
X712576Y547837D01*
X707336D01*
G01X744083Y558046D02*
X749323D01*
G01X746703D02*
Y540546D01*
G01X744083D02*
X749323D01*
G01X758526D02*
Y558046D01*
X764203Y543463D01*
X769880Y558046D01*
Y540546D01*
G01X777336D02*
Y558046D01*
X782576D01*
X784323Y557171D01*
X785633Y555129D01*
X786070Y552796D01*
X785633Y550463D01*
X784541Y548713D01*
X782576Y547837D01*
X777336D01*
G01X803570Y540546D02*
X794836D01*
Y558046D01*
X803570D01*
G01X800076Y549588D02*
X794836D01*
G01X811900Y540546D02*
Y558046D01*
X816266D01*
X818013Y557171D01*
X819323Y556004D01*
X820415Y554255D01*
X821288Y552212D01*
X821506Y549296D01*
X821288Y546379D01*
X820415Y544337D01*
X819323Y542587D01*
X818013Y541421D01*
X816266Y540546D01*
X811900D01*
G01X828744D02*
X834203Y558046D01*
X839662Y540546D01*
G01X837696Y546671D02*
X830709D01*
G01X846681Y540546D02*
Y558046D01*
X856725Y540546D01*
Y558046D01*
G01X874006Y556587D02*
X872696Y557463D01*
X871168Y558046D01*
X869421D01*
X867456Y557171D01*
X865928Y555713D01*
X864836Y553962D01*
X863963Y551046D01*
X863744Y548421D01*
X864181Y545796D01*
X864836Y544046D01*
X866146Y542296D01*
X867675Y541129D01*
X869203Y540546D01*
X870731D01*
X872260Y541129D01*
X873570Y542004D01*
X874662Y543170D01*
G01X891070Y540546D02*
X882336D01*
Y558046D01*
X891070D01*
G01X887576Y549588D02*
X882336D01*
G01X921703Y558046D02*
Y540546D01*
G01X916681Y558046D02*
X926725D01*
G01X933744Y540546D02*
X939203Y558046D01*
X944662Y540546D01*
G01X942696Y546671D02*
X935709D01*
G01X958449Y549879D02*
X959323Y550754D01*
X959978Y552212D01*
X960415Y554255D01*
X959978Y556004D01*
X959105Y557171D01*
X957576Y558046D01*
X951681D01*
Y540546D01*
X958886D01*
X960415Y541712D01*
X961288Y543463D01*
X961725Y545504D01*
X961288Y547546D01*
X959978Y549296D01*
X958449Y549879D01*
X951681D01*
G01X969836Y558046D02*
Y540546D01*
X978570D01*
G01X996070D02*
X987336D01*
Y558046D01*
X996070D01*
G01X992576Y549588D02*
X987336D01*
G01X1009203Y539963D02*
X1008766Y540254D01*
Y540838D01*
X1009203Y541129D01*
X1009640Y540838D01*
Y540254D01*
X1009203Y539963D01*
G01Y547837D02*
X1008766Y548129D01*
Y548713D01*
X1009203Y549004D01*
X1009640Y548713D01*
Y548129D01*
X1009203Y547837D01*
G01X1039836Y558046D02*
Y540546D01*
X1048570D01*
G01X1057555Y547837D02*
X1059083Y549879D01*
X1060393Y551046D01*
X1062140Y551629D01*
X1063668Y551046D01*
X1064760Y549879D01*
X1065633Y548129D01*
X1065851Y546088D01*
X1065633Y544337D01*
X1064760Y542587D01*
X1063449Y541129D01*
X1061921Y540546D01*
X1060175Y541129D01*
X1058646Y542879D01*
X1057773Y545504D01*
X1057555Y548421D01*
X1057991Y552212D01*
X1058646Y554255D01*
X1059738Y556296D01*
X1061266Y557754D01*
X1062795Y558046D01*
X1064323Y557463D01*
X1065415Y556004D01*
G01X711283Y523396D02*
X716523D01*
G01X713903D02*
Y505896D01*
G01X711283D02*
X716523D01*
G01X725726D02*
Y523396D01*
X731403Y508813D01*
X737080Y523396D01*
Y505896D01*
G01X744536D02*
Y523396D01*
X749776D01*
X751523Y522521D01*
X752833Y520479D01*
X753270Y518146D01*
X752833Y515813D01*
X751741Y514063D01*
X749776Y513187D01*
X744536D01*
G01X765311Y500063D02*
X763128Y502979D01*
X762036Y505896D01*
Y517562D01*
X763128Y520479D01*
X765311Y523396D01*
G01X783903Y505896D02*
X782156Y506188D01*
X780628Y507354D01*
X779318Y509104D01*
X778444Y511146D01*
X778008Y513479D01*
Y515813D01*
X778444Y518146D01*
X779318Y520188D01*
X780628Y521937D01*
X782156Y523104D01*
X783903Y523396D01*
X785649Y523104D01*
X787178Y521937D01*
X788488Y520188D01*
X789362Y518146D01*
X789798Y515813D01*
Y513479D01*
X789362Y511146D01*
X788488Y509104D01*
X787178Y507354D01*
X785649Y506188D01*
X783903Y505896D01*
G01X797691D02*
Y523396D01*
G01Y514938D02*
X798783Y516396D01*
X799875Y517271D01*
X801621Y517562D01*
X802931Y517271D01*
X804460Y516104D01*
X805115Y514354D01*
Y505896D01*
G01X812353D02*
Y517562D01*
G01Y514354D02*
X813008Y515813D01*
X814100Y516979D01*
X815628Y517562D01*
X817156Y516979D01*
X818248Y515813D01*
X818903Y514354D01*
Y505896D01*
G01Y514354D02*
X819558Y515813D01*
X820649Y516979D01*
X822178Y517562D01*
X823706Y516979D01*
X824798Y515813D01*
X825453Y514063D01*
Y505896D01*
G01X837495Y500063D02*
X839678Y502979D01*
X840770Y505896D01*
Y517562D01*
X839678Y520479D01*
X837495Y523396D01*
G01X891103D02*
X894159Y505896D01*
X897653Y523396D01*
X901146Y505896D01*
X904203Y523396D01*
G01X912533D02*
X917773D01*
G01X915153D02*
Y505896D01*
G01X912533D02*
X917773D01*
G01X927850D02*
Y523396D01*
X932216D01*
X933963Y522521D01*
X935273Y521354D01*
X936365Y519605D01*
X937238Y517562D01*
X937456Y514646D01*
X937238Y511729D01*
X936365Y509687D01*
X935273Y507937D01*
X933963Y506771D01*
X932216Y505896D01*
X927850D01*
G01X950153Y523396D02*
Y505896D01*
G01X945131Y523396D02*
X955175D01*
G01X963068Y505896D02*
Y523396D01*
G01X972238D02*
Y505896D01*
G01Y514646D02*
X963068D01*
G01X984061Y500063D02*
X981878Y502979D01*
X980786Y505896D01*
Y517562D01*
X981878Y520479D01*
X984061Y523396D01*
G01X996103Y505896D02*
Y517562D01*
G01Y514354D02*
X996758Y515813D01*
X997850Y516979D01*
X999378Y517562D01*
X1000906Y516979D01*
X1001998Y515813D01*
X1002653Y514354D01*
Y505896D01*
G01Y514354D02*
X1003308Y515813D01*
X1004399Y516979D01*
X1005928Y517562D01*
X1007456Y516979D01*
X1008548Y515813D01*
X1009203Y514063D01*
Y505896D01*
G01X1020153Y517562D02*
Y505896D01*
G01Y522229D02*
X1019716Y522521D01*
Y523104D01*
X1020153Y523396D01*
X1020590Y523104D01*
Y522521D01*
X1020153Y522229D01*
G01X1037653Y505896D02*
Y523396D01*
G01X1051878Y507937D02*
X1052970Y506771D01*
X1054498Y505896D01*
X1055808D01*
X1057118Y506479D01*
X1057991Y507354D01*
X1058428Y508520D01*
X1058210Y510271D01*
X1057336Y511146D01*
X1053406Y512896D01*
X1052533Y514938D01*
X1052970Y516396D01*
X1053843Y517271D01*
X1055153Y517562D01*
X1056463Y517271D01*
X1057773Y516396D01*
G01X1073745Y500063D02*
X1075928Y502979D01*
X1077020Y505896D01*
Y517562D01*
X1075928Y520479D01*
X1073745Y523396D01*
G01X927850Y473870D02*
X929159Y472412D01*
X930688Y471538D01*
X932653Y471246D01*
X934618Y471829D01*
X936146Y472996D01*
X937238Y475037D01*
X937456Y477371D01*
X937020Y479704D01*
X935928Y481163D01*
X934399Y482329D01*
X932871Y482621D01*
X931343Y482329D01*
X929378Y481163D01*
X930033Y488746D01*
X935928D01*
G01X950153Y470663D02*
X949716Y470954D01*
Y471538D01*
X950153Y471829D01*
X950590Y471538D01*
Y470954D01*
X950153Y470663D01*
G01X967653Y488746D02*
X965906Y488163D01*
X964596Y486704D01*
X963723Y484955D01*
X963068Y482621D01*
X962850Y479996D01*
X963068Y477371D01*
X963723Y475037D01*
X964596Y473287D01*
X965906Y471829D01*
X967653Y471246D01*
X969399Y471829D01*
X970710Y473287D01*
X971583Y475037D01*
X972238Y477371D01*
X972456Y479996D01*
X972238Y482621D01*
X971583Y484955D01*
X970710Y486704D01*
X969399Y488163D01*
X967653Y488746D01*
G01X981223Y470663D02*
X989083Y488746D01*
G01X1002216Y471246D02*
X1002653Y475037D01*
X1003308Y478246D01*
X1004181Y481163D01*
X1005273Y484371D01*
X1007020Y488746D01*
X998286D01*
G01X1020153Y470663D02*
X1019716Y470954D01*
Y471538D01*
X1020153Y471829D01*
X1020590Y471538D01*
Y470954D01*
X1020153Y470663D01*
G01X1037653Y488746D02*
X1035906Y488163D01*
X1034596Y486704D01*
X1033723Y484955D01*
X1033068Y482621D01*
X1032850Y479996D01*
X1033068Y477371D01*
X1033723Y475037D01*
X1034596Y473287D01*
X1035906Y471829D01*
X1037653Y471246D01*
X1039399Y471829D01*
X1040710Y473287D01*
X1041583Y475037D01*
X1042238Y477371D01*
X1042456Y479996D01*
X1042238Y482621D01*
X1041583Y484955D01*
X1040710Y486704D01*
X1039399Y488163D01*
X1037653Y488746D01*
G01X935273Y436596D02*
Y454096D01*
X927194Y441554D01*
X938112D01*
G01X950153Y436013D02*
X949716Y436304D01*
Y436888D01*
X950153Y437179D01*
X950590Y436888D01*
Y436304D01*
X950153Y436013D01*
G01X962850Y439220D02*
X964159Y437762D01*
X965688Y436888D01*
X967653Y436596D01*
X969618Y437179D01*
X971146Y438346D01*
X972238Y440387D01*
X972456Y442721D01*
X972020Y445054D01*
X970928Y446513D01*
X969399Y447679D01*
X967871Y447971D01*
X966343Y447679D01*
X964378Y446513D01*
X965033Y454096D01*
X970928D01*
G01X981223Y436013D02*
X989083Y454096D01*
G01X1002216Y436596D02*
X1002653Y440387D01*
X1003308Y443596D01*
X1004181Y446513D01*
X1005273Y449721D01*
X1007020Y454096D01*
X998286D01*
G01X1020153Y436013D02*
X1019716Y436304D01*
Y436888D01*
X1020153Y437179D01*
X1020590Y436888D01*
Y436304D01*
X1020153Y436013D01*
G01X1037653Y454096D02*
X1035906Y453513D01*
X1034596Y452054D01*
X1033723Y450305D01*
X1033068Y447971D01*
X1032850Y445346D01*
X1033068Y442721D01*
X1033723Y440387D01*
X1034596Y438637D01*
X1035906Y437179D01*
X1037653Y436596D01*
X1039399Y437179D01*
X1040710Y438637D01*
X1041583Y440387D01*
X1042238Y442721D01*
X1042456Y445346D01*
X1042238Y447971D01*
X1041583Y450305D01*
X1040710Y452054D01*
X1039399Y453513D01*
X1037653Y454096D01*
G01X1146600Y471246D02*
Y488746D01*
X1150966D01*
X1152713Y487871D01*
X1154023Y486704D01*
X1155115Y484955D01*
X1155988Y482912D01*
X1156206Y479996D01*
X1155988Y477079D01*
X1155115Y475037D01*
X1154023Y473287D01*
X1152713Y472121D01*
X1150966Y471246D01*
X1146600D01*
G01X1164536D02*
Y488746D01*
X1169776D01*
X1171523Y487871D01*
X1172833Y485829D01*
X1173270Y483496D01*
X1172833Y481163D01*
X1171741Y479413D01*
X1169776Y478537D01*
X1164536D01*
G01X1146600Y436596D02*
Y454096D01*
X1150966D01*
X1152713Y453221D01*
X1154023Y452054D01*
X1155115Y450305D01*
X1155988Y448262D01*
X1156206Y445346D01*
X1155988Y442429D01*
X1155115Y440387D01*
X1154023Y438637D01*
X1152713Y437471D01*
X1150966Y436596D01*
X1146600D01*
G01X1164536D02*
Y454096D01*
X1169776D01*
X1171523Y453221D01*
X1172833Y451179D01*
X1173270Y448846D01*
X1172833Y446513D01*
X1171741Y444763D01*
X1169776Y443887D01*
X1164536D01*
G01X1133903Y523396D02*
Y505896D01*
G01X1128881Y523396D02*
X1138925D01*
G01X1151403Y505896D02*
Y513771D01*
X1147036Y523396D01*
G01X1155770D02*
X1151403Y513771D01*
G01X1164536Y505896D02*
Y523396D01*
X1169776D01*
X1171523Y522521D01*
X1172833Y520479D01*
X1173270Y518146D01*
X1172833Y515813D01*
X1171741Y514063D01*
X1169776Y513187D01*
X1164536D01*
G01X1190770Y505896D02*
X1182036D01*
Y523396D01*
X1190770D01*
G01X1187276Y514938D02*
X1182036D01*
G01X1339203Y482912D02*
Y471246D01*
G01Y487579D02*
X1338766Y487871D01*
Y488454D01*
X1339203Y488746D01*
X1339640Y488454D01*
Y487871D01*
X1339203Y487579D01*
G01X1353428Y473287D02*
X1354520Y472121D01*
X1356048Y471246D01*
X1357358D01*
X1358668Y471829D01*
X1359541Y472704D01*
X1359978Y473870D01*
X1359760Y475621D01*
X1358886Y476496D01*
X1354956Y478246D01*
X1354083Y480288D01*
X1354520Y481746D01*
X1355393Y482621D01*
X1356703Y482912D01*
X1358013Y482621D01*
X1359323Y481746D01*
G01X1386681Y471246D02*
Y488746D01*
X1396725Y471246D01*
Y488746D01*
G01X1409203Y471246D02*
X1407456Y471538D01*
X1405928Y472704D01*
X1404618Y474454D01*
X1403744Y476496D01*
X1403308Y478829D01*
Y481163D01*
X1403744Y483496D01*
X1404618Y485538D01*
X1405928Y487287D01*
X1407456Y488454D01*
X1409203Y488746D01*
X1410949Y488454D01*
X1412478Y487287D01*
X1413788Y485538D01*
X1414662Y483496D01*
X1415098Y481163D01*
Y478829D01*
X1414662Y476496D01*
X1413788Y474454D01*
X1412478Y472704D01*
X1410949Y471538D01*
X1409203Y471246D01*
G01X1426703Y488746D02*
Y471246D01*
G01X1421681Y488746D02*
X1431725D01*
G01X1457991Y482912D02*
Y474746D01*
X1458865Y472704D01*
X1460175Y471538D01*
X1461703Y471246D01*
X1463231Y471538D01*
X1464541Y472704D01*
X1465415Y474746D01*
G01Y471246D02*
Y482912D01*
G01X1475928Y473287D02*
X1477020Y472121D01*
X1478548Y471246D01*
X1479858D01*
X1481168Y471829D01*
X1482041Y472704D01*
X1482478Y473870D01*
X1482260Y475621D01*
X1481386Y476496D01*
X1477456Y478246D01*
X1476583Y480288D01*
X1477020Y481746D01*
X1477893Y482621D01*
X1479203Y482912D01*
X1480513Y482621D01*
X1481823Y481746D01*
G01X1493428Y479121D02*
X1500415D01*
X1499760Y481163D01*
X1498668Y482329D01*
X1497140Y482912D01*
X1495611Y482621D01*
X1494301Y481746D01*
X1493428Y479704D01*
X1492991Y477954D01*
Y476204D01*
X1493428Y474454D01*
X1494520Y472704D01*
X1495830Y471538D01*
X1497358Y471246D01*
X1498886Y471829D01*
X1500415Y473579D01*
G01X1518133Y488746D02*
Y471246D01*
G01Y473870D02*
X1517260Y472412D01*
X1515949Y471538D01*
X1514421Y471246D01*
X1512675Y471829D01*
X1511365Y473287D01*
X1510491Y475037D01*
X1510273Y477079D01*
X1510491Y479121D01*
X1511365Y480871D01*
X1512675Y482329D01*
X1514421Y482912D01*
X1515949Y482621D01*
X1517041Y482037D01*
X1518133Y480871D01*
G01X1264400Y505313D02*
X1274006Y518146D01*
G01X1269203Y520479D02*
Y502979D01*
G01X1274006Y505313D02*
X1264400Y518146D01*
G01X1262653Y511729D02*
X1275753D01*
G01X1301365D02*
X1307041D01*
G01X1334400Y505896D02*
Y523396D01*
X1338766D01*
X1340513Y522521D01*
X1341823Y521354D01*
X1342915Y519605D01*
X1343788Y517562D01*
X1344006Y514646D01*
X1343788Y511729D01*
X1342915Y509687D01*
X1341823Y507937D01*
X1340513Y506771D01*
X1338766Y505896D01*
X1334400D01*
G01X1353428Y513771D02*
X1360415D01*
X1359760Y515813D01*
X1358668Y516979D01*
X1357140Y517562D01*
X1355611Y517271D01*
X1354301Y516396D01*
X1353428Y514354D01*
X1352991Y512604D01*
Y510854D01*
X1353428Y509104D01*
X1354520Y507354D01*
X1355830Y506188D01*
X1357358Y505896D01*
X1358886Y506479D01*
X1360415Y508229D01*
G01X1370491Y505896D02*
Y517562D01*
G01Y514646D02*
X1371365Y516104D01*
X1372675Y517271D01*
X1374421Y517562D01*
X1375949Y517271D01*
X1377260Y516104D01*
X1377915Y514063D01*
Y505896D01*
G01X1391703D02*
X1390393Y506188D01*
X1389083Y507354D01*
X1388209Y509396D01*
X1387773Y511729D01*
X1388209Y514063D01*
X1389083Y516104D01*
X1390393Y517271D01*
X1391703Y517562D01*
X1393013Y517271D01*
X1394323Y516104D01*
X1395196Y514063D01*
X1395415Y511729D01*
X1395196Y509396D01*
X1394323Y507354D01*
X1393013Y506188D01*
X1391703Y505896D01*
G01X1409203Y523396D02*
Y505896D01*
G01X1406146Y517562D02*
X1412260D01*
G01X1423428Y513771D02*
X1430415D01*
X1429760Y515813D01*
X1428668Y516979D01*
X1427140Y517562D01*
X1425611Y517271D01*
X1424301Y516396D01*
X1423428Y514354D01*
X1422991Y512604D01*
Y510854D01*
X1423428Y509104D01*
X1424520Y507354D01*
X1425830Y506188D01*
X1427358Y505896D01*
X1428886Y506479D01*
X1430415Y508229D01*
G01X1440928Y507937D02*
X1442020Y506771D01*
X1443548Y505896D01*
X1444858D01*
X1446168Y506479D01*
X1447041Y507354D01*
X1447478Y508520D01*
X1447260Y510271D01*
X1446386Y511146D01*
X1442456Y512896D01*
X1441583Y514938D01*
X1442020Y516396D01*
X1442893Y517271D01*
X1444203Y517562D01*
X1445513Y517271D01*
X1446823Y516396D01*
G01X1479203Y523396D02*
Y505896D01*
G01X1476146Y517562D02*
X1482260D01*
G01X1492991Y505896D02*
Y523396D01*
G01Y514938D02*
X1494083Y516396D01*
X1495175Y517271D01*
X1496921Y517562D01*
X1498231Y517271D01*
X1499760Y516104D01*
X1500415Y514354D01*
Y505896D01*
G01X1518133D02*
Y517562D01*
G01Y515521D02*
X1517260Y516687D01*
X1515949Y517271D01*
X1514421Y517562D01*
X1512893Y516979D01*
X1511583Y515813D01*
X1510709Y514063D01*
X1510273Y511729D01*
X1510709Y509396D01*
X1511583Y507646D01*
X1512893Y506479D01*
X1514421Y505896D01*
X1515949Y506188D01*
X1517260Y507062D01*
X1518133Y508229D01*
G01X1531703Y523396D02*
Y505896D01*
G01X1528646Y517562D02*
X1534760D01*
G01X1566703Y523396D02*
Y505896D01*
G01X1563646Y517562D02*
X1569760D01*
G01X1580491Y505896D02*
Y523396D01*
G01Y514938D02*
X1581583Y516396D01*
X1582675Y517271D01*
X1584421Y517562D01*
X1585731Y517271D01*
X1587260Y516104D01*
X1587915Y514354D01*
Y505896D01*
G01X1601703Y517562D02*
Y505896D01*
G01Y522229D02*
X1601266Y522521D01*
Y523104D01*
X1601703Y523396D01*
X1602140Y523104D01*
Y522521D01*
X1601703Y522229D01*
G01X1615928Y507937D02*
X1617020Y506771D01*
X1618548Y505896D01*
X1619858D01*
X1621168Y506479D01*
X1622041Y507354D01*
X1622478Y508520D01*
X1622260Y510271D01*
X1621386Y511146D01*
X1617456Y512896D01*
X1616583Y514938D01*
X1617020Y516396D01*
X1617893Y517271D01*
X1619203Y517562D01*
X1620513Y517271D01*
X1621823Y516396D01*
G01X1651583Y523396D02*
X1656823D01*
G01X1654203D02*
Y505896D01*
G01X1651583D02*
X1656823D01*
G01X1665153D02*
Y517562D01*
G01Y514354D02*
X1665808Y515813D01*
X1666900Y516979D01*
X1668428Y517562D01*
X1669956Y516979D01*
X1671048Y515813D01*
X1671703Y514354D01*
Y505896D01*
G01Y514354D02*
X1672358Y515813D01*
X1673449Y516979D01*
X1674978Y517562D01*
X1676506Y516979D01*
X1677598Y515813D01*
X1678253Y514063D01*
Y505896D01*
G01X1685273Y500063D02*
Y517562D01*
G01Y514938D02*
X1686365Y516396D01*
X1687456Y517271D01*
X1689203Y517562D01*
X1690731Y517271D01*
X1692260Y515813D01*
X1692915Y513771D01*
X1693133Y511729D01*
X1692915Y509687D01*
X1692260Y507646D01*
X1690949Y506479D01*
X1689203Y505896D01*
X1687675Y506188D01*
X1686146Y507062D01*
X1685273Y508229D01*
G01X1703428Y513771D02*
X1710415D01*
X1709760Y515813D01*
X1708668Y516979D01*
X1707140Y517562D01*
X1705611Y517271D01*
X1704301Y516396D01*
X1703428Y514354D01*
X1702991Y512604D01*
Y510854D01*
X1703428Y509104D01*
X1704520Y507354D01*
X1705830Y506188D01*
X1707358Y505896D01*
X1708886Y506479D01*
X1710415Y508229D01*
G01X1728133Y523396D02*
Y505896D01*
G01Y508520D02*
X1727260Y507062D01*
X1725949Y506188D01*
X1724421Y505896D01*
X1722675Y506479D01*
X1721365Y507937D01*
X1720491Y509687D01*
X1720273Y511729D01*
X1720491Y513771D01*
X1721365Y515521D01*
X1722675Y516979D01*
X1724421Y517562D01*
X1725949Y517271D01*
X1727041Y516687D01*
X1728133Y515521D01*
G01X1745633Y505896D02*
Y517562D01*
G01Y515521D02*
X1744760Y516687D01*
X1743449Y517271D01*
X1741921Y517562D01*
X1740393Y516979D01*
X1739083Y515813D01*
X1738209Y514063D01*
X1737773Y511729D01*
X1738209Y509396D01*
X1739083Y507646D01*
X1740393Y506479D01*
X1741921Y505896D01*
X1743449Y506188D01*
X1744760Y507062D01*
X1745633Y508229D01*
G01X1755491Y505896D02*
Y517562D01*
G01Y514646D02*
X1756365Y516104D01*
X1757675Y517271D01*
X1759421Y517562D01*
X1760949Y517271D01*
X1762260Y516104D01*
X1762915Y514063D01*
Y505896D01*
G01X1780196Y516104D02*
X1778668Y517271D01*
X1777358Y517562D01*
X1775611Y516979D01*
X1774301Y515813D01*
X1773428Y513771D01*
X1773209Y511729D01*
X1773428Y509687D01*
X1774301Y507937D01*
X1775611Y506479D01*
X1777358Y505896D01*
X1778886Y506479D01*
X1780196Y507646D01*
G01X1790928Y513771D02*
X1797915D01*
X1797260Y515813D01*
X1796168Y516979D01*
X1794640Y517562D01*
X1793111Y517271D01*
X1791801Y516396D01*
X1790928Y514354D01*
X1790491Y512604D01*
Y510854D01*
X1790928Y509104D01*
X1792020Y507354D01*
X1793330Y506188D01*
X1794858Y505896D01*
X1796386Y506479D01*
X1797915Y508229D01*
M02*
